FILE_TYPE = MACRO_DRAWING;
SET COLOR_WIRE YELLOW;
SET COLOR_PROP MONO;
SET COLOR_DOT WHITE;
SET COLOR_ARC YELLOW;
SET COLOR_BODY GREEN;
SET COLOR_NOTE MONO;
SET PROP_DISPLAY VALUE;
SET PAGE_NUMBER P117;
FORCEADD TAP..6
(-5500 2400);
FORCEPROP 3 LASTPIN (-5450 2400) SIG_NAME P3E_CPU0_PE1_PCH_C_TXN<12>
J 0
(-5440 2410);
DISPLAY 0.659574 (-5440 2410);
PAINT MONO (-5440 2410);
DISPLAY INVISIBLE (-5440 2410);
FORCEPROP 1 LASTPIN (-5450 2400) BN 12
J 0
(-5502 2408);
DISPLAY 0.617021 (-5502 2408);
PAINT GREEN (-5502 2408);
FORCEPROP 2 LAST CDS_LIB mstr_standard
J 0
(-5500 2400);
PAINT ORANGE (-5500 2400);
DISPLAY INVISIBLE (-5500 2400);
FORCEPROP 1 LAST PATH I101
J 0
(-5502 2400);
DISPLAY 0.872340 (-5502 2400);
PAINT GREEN (-5502 2400);
DISPLAY INVISIBLE (-5502 2400);
FORCEPROP 1 LAST BODY_TYPE PLUMBING
J 0
(-5500 2350);
DISPLAY 1.170213 (-5500 2350);
PAINT GREEN (-5500 2350);
DISPLAY INVISIBLE (-5500 2350);
FORCEPROP 1 LAST HDL_TAP TRUE
J 0
(-5175 2275);
DISPLAY 1.170213 (-5175 2275);
PAINT ORANGE (-5175 2275);
DISPLAY INVISIBLE (-5175 2275);
FORCEADD TAP..6
(-5500 2500);
FORCEPROP 3 LASTPIN (-5450 2500) SIG_NAME P3E_CPU0_PE1_PCH_C_TXN<13>
J 0
(-5440 2510);
DISPLAY 0.659574 (-5440 2510);
PAINT MONO (-5440 2510);
DISPLAY INVISIBLE (-5440 2510);
FORCEPROP 1 LASTPIN (-5450 2500) BN 13
J 0
(-5502 2508);
DISPLAY 0.617021 (-5502 2508);
PAINT GREEN (-5502 2508);
FORCEPROP 2 LAST CDS_LIB mstr_standard
J 0
(-5500 2500);
PAINT ORANGE (-5500 2500);
DISPLAY INVISIBLE (-5500 2500);
FORCEPROP 1 LAST PATH I102
J 0
(-5502 2500);
DISPLAY 0.872340 (-5502 2500);
PAINT GREEN (-5502 2500);
DISPLAY INVISIBLE (-5502 2500);
FORCEPROP 1 LAST BODY_TYPE PLUMBING
J 0
(-5500 2450);
DISPLAY 1.170213 (-5500 2450);
PAINT GREEN (-5500 2450);
DISPLAY INVISIBLE (-5500 2450);
FORCEPROP 1 LAST HDL_TAP TRUE
J 0
(-5175 2375);
DISPLAY 1.170213 (-5175 2375);
PAINT ORANGE (-5175 2375);
DISPLAY INVISIBLE (-5175 2375);
FORCEADD TAP..6
(-5500 2600);
FORCEPROP 3 LASTPIN (-5450 2600) SIG_NAME P3E_CPU0_PE1_PCH_C_TXN<14>
J 0
(-5440 2610);
DISPLAY 0.659574 (-5440 2610);
PAINT MONO (-5440 2610);
DISPLAY INVISIBLE (-5440 2610);
FORCEPROP 1 LASTPIN (-5450 2600) BN 14
J 0
(-5502 2608);
DISPLAY 0.617021 (-5502 2608);
PAINT GREEN (-5502 2608);
FORCEPROP 2 LAST CDS_LIB mstr_standard
J 0
(-5500 2600);
PAINT ORANGE (-5500 2600);
DISPLAY INVISIBLE (-5500 2600);
FORCEPROP 1 LAST PATH I103
J 0
(-5502 2600);
DISPLAY 0.872340 (-5502 2600);
PAINT GREEN (-5502 2600);
DISPLAY INVISIBLE (-5502 2600);
FORCEPROP 1 LAST BODY_TYPE PLUMBING
J 0
(-5500 2550);
DISPLAY 1.170213 (-5500 2550);
PAINT GREEN (-5500 2550);
DISPLAY INVISIBLE (-5500 2550);
FORCEPROP 1 LAST HDL_TAP TRUE
J 0
(-5175 2475);
DISPLAY 1.170213 (-5175 2475);
PAINT ORANGE (-5175 2475);
DISPLAY INVISIBLE (-5175 2475);
FORCEADD TAP..6
(-5500 2700);
FORCEPROP 3 LASTPIN (-5450 2700) SIG_NAME P3E_CPU0_PE1_PCH_C_TXN<15>
J 0
(-5440 2710);
DISPLAY 0.659574 (-5440 2710);
PAINT MONO (-5440 2710);
DISPLAY INVISIBLE (-5440 2710);
FORCEPROP 1 LASTPIN (-5450 2700) BN 15
J 0
(-5502 2708);
DISPLAY 0.617021 (-5502 2708);
PAINT GREEN (-5502 2708);
FORCEPROP 2 LAST CDS_LIB mstr_standard
J 0
(-5500 2700);
PAINT ORANGE (-5500 2700);
DISPLAY INVISIBLE (-5500 2700);
FORCEPROP 1 LAST PATH I104
J 0
(-5502 2700);
DISPLAY 0.872340 (-5502 2700);
PAINT GREEN (-5502 2700);
DISPLAY INVISIBLE (-5502 2700);
FORCEPROP 1 LAST BODY_TYPE PLUMBING
J 0
(-5500 2650);
DISPLAY 1.170213 (-5500 2650);
PAINT GREEN (-5500 2650);
DISPLAY INVISIBLE (-5500 2650);
FORCEPROP 1 LAST HDL_TAP TRUE
J 0
(-5175 2575);
DISPLAY 1.170213 (-5175 2575);
PAINT ORANGE (-5175 2575);
DISPLAY INVISIBLE (-5175 2575);
FORCEADD TAP..6
(-5625 1950);
FORCEPROP 3 LASTPIN (-5575 1950) SIG_NAME P3E_CPU0_PE1_PCH_C_TXP<8>
J 0
(-5565 1960);
DISPLAY 0.659574 (-5565 1960);
PAINT MONO (-5565 1960);
DISPLAY INVISIBLE (-5565 1960);
FORCEPROP 1 LASTPIN (-5575 1950) BN 8
J 0
(-5627 1958);
DISPLAY 0.617021 (-5627 1958);
PAINT GREEN (-5627 1958);
FORCEPROP 2 LAST CDS_LIB mstr_standard
J 0
(-5625 1950);
PAINT ORANGE (-5625 1950);
DISPLAY INVISIBLE (-5625 1950);
FORCEPROP 1 LAST PATH I105
J 0
(-5627 1950);
DISPLAY 0.872340 (-5627 1950);
PAINT GREEN (-5627 1950);
DISPLAY INVISIBLE (-5627 1950);
FORCEPROP 1 LAST BODY_TYPE PLUMBING
J 0
(-5625 1900);
DISPLAY 1.170213 (-5625 1900);
PAINT GREEN (-5625 1900);
DISPLAY INVISIBLE (-5625 1900);
FORCEPROP 1 LAST HDL_TAP TRUE
J 0
(-5300 1825);
DISPLAY 1.170213 (-5300 1825);
PAINT ORANGE (-5300 1825);
DISPLAY INVISIBLE (-5300 1825);
FORCEADD TAP..6
(-5625 2050);
FORCEPROP 3 LASTPIN (-5575 2050) SIG_NAME P3E_CPU0_PE1_PCH_C_TXP<9>
J 0
(-5565 2060);
DISPLAY 0.659574 (-5565 2060);
PAINT MONO (-5565 2060);
DISPLAY INVISIBLE (-5565 2060);
FORCEPROP 1 LASTPIN (-5575 2050) BN 9
J 0
(-5627 2058);
DISPLAY 0.617021 (-5627 2058);
PAINT GREEN (-5627 2058);
FORCEPROP 2 LAST CDS_LIB mstr_standard
J 0
(-5625 2050);
PAINT ORANGE (-5625 2050);
DISPLAY INVISIBLE (-5625 2050);
FORCEPROP 1 LAST PATH I106
J 0
(-5627 2050);
DISPLAY 0.872340 (-5627 2050);
PAINT GREEN (-5627 2050);
DISPLAY INVISIBLE (-5627 2050);
FORCEPROP 1 LAST BODY_TYPE PLUMBING
J 0
(-5625 2000);
DISPLAY 1.170213 (-5625 2000);
PAINT GREEN (-5625 2000);
DISPLAY INVISIBLE (-5625 2000);
FORCEPROP 1 LAST HDL_TAP TRUE
J 0
(-5300 1925);
DISPLAY 1.170213 (-5300 1925);
PAINT ORANGE (-5300 1925);
DISPLAY INVISIBLE (-5300 1925);
FORCEADD TAP..6
(-5625 2150);
FORCEPROP 3 LASTPIN (-5575 2150) SIG_NAME P3E_CPU0_PE1_PCH_C_TXP<10>
J 0
(-5565 2160);
DISPLAY 0.659574 (-5565 2160);
PAINT MONO (-5565 2160);
DISPLAY INVISIBLE (-5565 2160);
FORCEPROP 1 LASTPIN (-5575 2150) BN 10
J 0
(-5627 2158);
DISPLAY 0.617021 (-5627 2158);
PAINT GREEN (-5627 2158);
FORCEPROP 2 LAST CDS_LIB mstr_standard
J 0
(-5625 2150);
PAINT ORANGE (-5625 2150);
DISPLAY INVISIBLE (-5625 2150);
FORCEPROP 1 LAST PATH I107
J 0
(-5627 2150);
DISPLAY 0.872340 (-5627 2150);
PAINT GREEN (-5627 2150);
DISPLAY INVISIBLE (-5627 2150);
FORCEPROP 1 LAST BODY_TYPE PLUMBING
J 0
(-5625 2100);
DISPLAY 1.170213 (-5625 2100);
PAINT GREEN (-5625 2100);
DISPLAY INVISIBLE (-5625 2100);
FORCEPROP 1 LAST HDL_TAP TRUE
J 0
(-5300 2025);
DISPLAY 1.170213 (-5300 2025);
PAINT ORANGE (-5300 2025);
DISPLAY INVISIBLE (-5300 2025);
FORCEADD TAP..6
(-5625 2350);
FORCEPROP 3 LASTPIN (-5575 2350) SIG_NAME P3E_CPU0_PE1_PCH_C_TXP<12>
J 0
(-5565 2360);
DISPLAY 0.659574 (-5565 2360);
PAINT MONO (-5565 2360);
DISPLAY INVISIBLE (-5565 2360);
FORCEPROP 1 LASTPIN (-5575 2350) BN 12
J 0
(-5627 2358);
DISPLAY 0.617021 (-5627 2358);
PAINT GREEN (-5627 2358);
FORCEPROP 2 LAST CDS_LIB mstr_standard
J 0
(-5625 2350);
PAINT ORANGE (-5625 2350);
DISPLAY INVISIBLE (-5625 2350);
FORCEPROP 1 LAST PATH I109
J 0
(-5627 2350);
DISPLAY 0.872340 (-5627 2350);
PAINT GREEN (-5627 2350);
DISPLAY INVISIBLE (-5627 2350);
FORCEPROP 1 LAST BODY_TYPE PLUMBING
J 0
(-5625 2300);
DISPLAY 1.170213 (-5625 2300);
PAINT GREEN (-5625 2300);
DISPLAY INVISIBLE (-5625 2300);
FORCEPROP 1 LAST HDL_TAP TRUE
J 0
(-5300 2225);
DISPLAY 1.170213 (-5300 2225);
PAINT ORANGE (-5300 2225);
DISPLAY INVISIBLE (-5300 2225);
FORCEADD TAP..6
(-5625 2450);
FORCEPROP 3 LASTPIN (-5575 2450) SIG_NAME P3E_CPU0_PE1_PCH_C_TXP<13>
J 0
(-5565 2460);
DISPLAY 0.659574 (-5565 2460);
PAINT MONO (-5565 2460);
DISPLAY INVISIBLE (-5565 2460);
FORCEPROP 1 LASTPIN (-5575 2450) BN 13
J 0
(-5627 2458);
DISPLAY 0.617021 (-5627 2458);
PAINT GREEN (-5627 2458);
FORCEPROP 2 LAST CDS_LIB mstr_standard
J 0
(-5625 2450);
PAINT ORANGE (-5625 2450);
DISPLAY INVISIBLE (-5625 2450);
FORCEPROP 1 LAST PATH I110
J 0
(-5627 2450);
DISPLAY 0.872340 (-5627 2450);
PAINT GREEN (-5627 2450);
DISPLAY INVISIBLE (-5627 2450);
FORCEPROP 1 LAST BODY_TYPE PLUMBING
J 0
(-5625 2400);
DISPLAY 1.170213 (-5625 2400);
PAINT GREEN (-5625 2400);
DISPLAY INVISIBLE (-5625 2400);
FORCEPROP 1 LAST HDL_TAP TRUE
J 0
(-5300 2325);
DISPLAY 1.170213 (-5300 2325);
PAINT ORANGE (-5300 2325);
DISPLAY INVISIBLE (-5300 2325);
FORCEADD TAP..6
(-5625 2550);
FORCEPROP 3 LASTPIN (-5575 2550) SIG_NAME P3E_CPU0_PE1_PCH_C_TXP<14>
J 0
(-5565 2560);
DISPLAY 0.659574 (-5565 2560);
PAINT MONO (-5565 2560);
DISPLAY INVISIBLE (-5565 2560);
FORCEPROP 1 LASTPIN (-5575 2550) BN 14
J 0
(-5627 2558);
DISPLAY 0.617021 (-5627 2558);
PAINT GREEN (-5627 2558);
FORCEPROP 2 LAST CDS_LIB mstr_standard
J 0
(-5625 2550);
PAINT ORANGE (-5625 2550);
DISPLAY INVISIBLE (-5625 2550);
FORCEPROP 1 LAST PATH I111
J 0
(-5627 2550);
DISPLAY 0.872340 (-5627 2550);
PAINT GREEN (-5627 2550);
DISPLAY INVISIBLE (-5627 2550);
FORCEPROP 1 LAST BODY_TYPE PLUMBING
J 0
(-5625 2500);
DISPLAY 1.170213 (-5625 2500);
PAINT GREEN (-5625 2500);
DISPLAY INVISIBLE (-5625 2500);
FORCEPROP 1 LAST HDL_TAP TRUE
J 0
(-5300 2425);
DISPLAY 1.170213 (-5300 2425);
PAINT ORANGE (-5300 2425);
DISPLAY INVISIBLE (-5300 2425);
FORCEADD TAP..6
(-5625 2650);
FORCEPROP 3 LASTPIN (-5575 2650) SIG_NAME P3E_CPU0_PE1_PCH_C_TXP<15>
J 0
(-5565 2660);
DISPLAY 0.659574 (-5565 2660);
PAINT MONO (-5565 2660);
DISPLAY INVISIBLE (-5565 2660);
FORCEPROP 1 LASTPIN (-5575 2650) BN 15
J 0
(-5627 2658);
DISPLAY 0.617021 (-5627 2658);
PAINT GREEN (-5627 2658);
FORCEPROP 2 LAST CDS_LIB mstr_standard
J 0
(-5625 2650);
PAINT ORANGE (-5625 2650);
DISPLAY INVISIBLE (-5625 2650);
FORCEPROP 1 LAST PATH I112
J 0
(-5627 2650);
DISPLAY 0.872340 (-5627 2650);
PAINT GREEN (-5627 2650);
DISPLAY INVISIBLE (-5627 2650);
FORCEPROP 1 LAST BODY_TYPE PLUMBING
J 0
(-5625 2600);
DISPLAY 1.170213 (-5625 2600);
PAINT GREEN (-5625 2600);
DISPLAY INVISIBLE (-5625 2600);
FORCEPROP 1 LAST HDL_TAP TRUE
J 0
(-5300 2525);
DISPLAY 1.170213 (-5300 2525);
PAINT ORANGE (-5300 2525);
DISPLAY INVISIBLE (-5300 2525);
FORCEADD TAP..1
(-2600 1950);
FORCEPROP 3 LASTPIN (-2650 1950) SIG_NAME P3E_CPU0_PE1_PCH_R_RXN<8>
J 0
(-2640 1960);
DISPLAY 0.659574 (-2640 1960);
PAINT MONO (-2640 1960);
DISPLAY INVISIBLE (-2640 1960);
FORCEPROP 1 LASTPIN (-2650 1950) BN 8
J 0
(-2662 1958);
DISPLAY 0.617021 (-2662 1958);
PAINT GREEN (-2662 1958);
FORCEPROP 2 LAST CDS_LIB mstr_standard
J 0
(-2600 1950);
PAINT ORANGE (-2600 1950);
DISPLAY INVISIBLE (-2600 1950);
FORCEPROP 1 LAST PATH I113
J 0
(-2602 1950);
DISPLAY 0.872340 (-2602 1950);
PAINT GREEN (-2602 1950);
DISPLAY INVISIBLE (-2602 1950);
FORCEPROP 1 LAST BODY_TYPE PLUMBING
J 0
(-2600 2000);
DISPLAY 1.170213 (-2600 2000);
PAINT GREEN (-2600 2000);
DISPLAY INVISIBLE (-2600 2000);
FORCEPROP 1 LAST HDL_TAP TRUE
J 0
(-2275 1825);
DISPLAY 1.170213 (-2275 1825);
PAINT ORANGE (-2275 1825);
DISPLAY INVISIBLE (-2275 1825);
FORCEADD TAP..1
(-2600 2050);
FORCEPROP 3 LASTPIN (-2650 2050) SIG_NAME P3E_CPU0_PE1_PCH_R_RXN<9>
J 0
(-2640 2060);
DISPLAY 0.659574 (-2640 2060);
PAINT MONO (-2640 2060);
DISPLAY INVISIBLE (-2640 2060);
FORCEPROP 1 LASTPIN (-2650 2050) BN 9
J 0
(-2662 2058);
DISPLAY 0.617021 (-2662 2058);
PAINT GREEN (-2662 2058);
FORCEPROP 2 LAST CDS_LIB mstr_standard
J 0
(-2600 2050);
PAINT ORANGE (-2600 2050);
DISPLAY INVISIBLE (-2600 2050);
FORCEPROP 1 LAST PATH I114
J 0
(-2602 2050);
DISPLAY 0.872340 (-2602 2050);
PAINT GREEN (-2602 2050);
DISPLAY INVISIBLE (-2602 2050);
FORCEPROP 1 LAST BODY_TYPE PLUMBING
J 0
(-2600 2100);
DISPLAY 1.170213 (-2600 2100);
PAINT GREEN (-2600 2100);
DISPLAY INVISIBLE (-2600 2100);
FORCEPROP 1 LAST HDL_TAP TRUE
J 0
(-2275 1925);
DISPLAY 1.170213 (-2275 1925);
PAINT ORANGE (-2275 1925);
DISPLAY INVISIBLE (-2275 1925);
FORCEADD TAP..1
(-2600 2150);
FORCEPROP 3 LASTPIN (-2650 2150) SIG_NAME P3E_CPU0_PE1_PCH_R_RXN<10>
J 0
(-2640 2160);
DISPLAY 0.659574 (-2640 2160);
PAINT MONO (-2640 2160);
DISPLAY INVISIBLE (-2640 2160);
FORCEPROP 1 LASTPIN (-2650 2150) BN 10
J 0
(-2662 2158);
DISPLAY 0.617021 (-2662 2158);
PAINT GREEN (-2662 2158);
FORCEPROP 2 LAST CDS_LIB mstr_standard
J 0
(-2600 2150);
PAINT ORANGE (-2600 2150);
DISPLAY INVISIBLE (-2600 2150);
FORCEPROP 1 LAST PATH I115
J 0
(-2602 2150);
DISPLAY 0.872340 (-2602 2150);
PAINT GREEN (-2602 2150);
DISPLAY INVISIBLE (-2602 2150);
FORCEPROP 1 LAST BODY_TYPE PLUMBING
J 0
(-2600 2200);
DISPLAY 1.170213 (-2600 2200);
PAINT GREEN (-2600 2200);
DISPLAY INVISIBLE (-2600 2200);
FORCEPROP 1 LAST HDL_TAP TRUE
J 0
(-2275 2025);
DISPLAY 1.170213 (-2275 2025);
PAINT ORANGE (-2275 2025);
DISPLAY INVISIBLE (-2275 2025);
FORCEADD TAP..1
(-2600 2250);
FORCEPROP 3 LASTPIN (-2650 2250) SIG_NAME P3E_CPU0_PE1_PCH_R_RXN<11>
J 0
(-2640 2260);
DISPLAY 0.659574 (-2640 2260);
PAINT MONO (-2640 2260);
DISPLAY INVISIBLE (-2640 2260);
FORCEPROP 1 LASTPIN (-2650 2250) BN 11
J 0
(-2662 2258);
DISPLAY 0.617021 (-2662 2258);
PAINT GREEN (-2662 2258);
FORCEPROP 2 LAST CDS_LIB mstr_standard
J 0
(-2600 2250);
PAINT ORANGE (-2600 2250);
DISPLAY INVISIBLE (-2600 2250);
FORCEPROP 1 LAST PATH I116
J 0
(-2602 2250);
DISPLAY 0.872340 (-2602 2250);
PAINT GREEN (-2602 2250);
DISPLAY INVISIBLE (-2602 2250);
FORCEPROP 1 LAST BODY_TYPE PLUMBING
J 0
(-2600 2300);
DISPLAY 1.170213 (-2600 2300);
PAINT GREEN (-2600 2300);
DISPLAY INVISIBLE (-2600 2300);
FORCEPROP 1 LAST HDL_TAP TRUE
J 0
(-2275 2125);
DISPLAY 1.170213 (-2275 2125);
PAINT ORANGE (-2275 2125);
DISPLAY INVISIBLE (-2275 2125);
FORCEADD TAP..1
(-2600 2350);
FORCEPROP 3 LASTPIN (-2650 2350) SIG_NAME P3E_CPU0_PE1_PCH_R_RXN<12>
J 0
(-2640 2360);
DISPLAY 0.659574 (-2640 2360);
PAINT MONO (-2640 2360);
DISPLAY INVISIBLE (-2640 2360);
FORCEPROP 1 LASTPIN (-2650 2350) BN 12
J 0
(-2662 2358);
DISPLAY 0.617021 (-2662 2358);
PAINT GREEN (-2662 2358);
FORCEPROP 2 LAST CDS_LIB mstr_standard
J 0
(-2600 2350);
PAINT ORANGE (-2600 2350);
DISPLAY INVISIBLE (-2600 2350);
FORCEPROP 1 LAST PATH I117
J 0
(-2602 2350);
DISPLAY 0.872340 (-2602 2350);
PAINT GREEN (-2602 2350);
DISPLAY INVISIBLE (-2602 2350);
FORCEPROP 1 LAST BODY_TYPE PLUMBING
J 0
(-2600 2400);
DISPLAY 1.170213 (-2600 2400);
PAINT GREEN (-2600 2400);
DISPLAY INVISIBLE (-2600 2400);
FORCEPROP 1 LAST HDL_TAP TRUE
J 0
(-2275 2225);
DISPLAY 1.170213 (-2275 2225);
PAINT ORANGE (-2275 2225);
DISPLAY INVISIBLE (-2275 2225);
FORCEADD TAP..1
(-2600 2450);
FORCEPROP 3 LASTPIN (-2650 2450) SIG_NAME P3E_CPU0_PE1_PCH_R_RXN<13>
J 0
(-2640 2460);
DISPLAY 0.659574 (-2640 2460);
PAINT MONO (-2640 2460);
DISPLAY INVISIBLE (-2640 2460);
FORCEPROP 1 LASTPIN (-2650 2450) BN 13
J 0
(-2662 2458);
DISPLAY 0.617021 (-2662 2458);
PAINT GREEN (-2662 2458);
FORCEPROP 2 LAST CDS_LIB mstr_standard
J 0
(-2600 2450);
PAINT ORANGE (-2600 2450);
DISPLAY INVISIBLE (-2600 2450);
FORCEPROP 1 LAST PATH I118
J 0
(-2602 2450);
DISPLAY 0.872340 (-2602 2450);
PAINT GREEN (-2602 2450);
DISPLAY INVISIBLE (-2602 2450);
FORCEPROP 1 LAST BODY_TYPE PLUMBING
J 0
(-2600 2500);
DISPLAY 1.170213 (-2600 2500);
PAINT GREEN (-2600 2500);
DISPLAY INVISIBLE (-2600 2500);
FORCEPROP 1 LAST HDL_TAP TRUE
J 0
(-2275 2325);
DISPLAY 1.170213 (-2275 2325);
PAINT ORANGE (-2275 2325);
DISPLAY INVISIBLE (-2275 2325);
FORCEADD TAP..1
(-2600 2550);
FORCEPROP 3 LASTPIN (-2650 2550) SIG_NAME P3E_CPU0_PE1_PCH_R_RXN<14>
J 0
(-2640 2560);
DISPLAY 0.659574 (-2640 2560);
PAINT MONO (-2640 2560);
DISPLAY INVISIBLE (-2640 2560);
FORCEPROP 1 LASTPIN (-2650 2550) BN 14
J 0
(-2662 2558);
DISPLAY 0.617021 (-2662 2558);
PAINT GREEN (-2662 2558);
FORCEPROP 2 LAST CDS_LIB mstr_standard
J 0
(-2600 2550);
PAINT ORANGE (-2600 2550);
DISPLAY INVISIBLE (-2600 2550);
FORCEPROP 1 LAST PATH I119
J 0
(-2602 2550);
DISPLAY 0.872340 (-2602 2550);
PAINT GREEN (-2602 2550);
DISPLAY INVISIBLE (-2602 2550);
FORCEPROP 1 LAST BODY_TYPE PLUMBING
J 0
(-2600 2600);
DISPLAY 1.170213 (-2600 2600);
PAINT GREEN (-2600 2600);
DISPLAY INVISIBLE (-2600 2600);
FORCEPROP 1 LAST HDL_TAP TRUE
J 0
(-2275 2425);
DISPLAY 1.170213 (-2275 2425);
PAINT ORANGE (-2275 2425);
DISPLAY INVISIBLE (-2275 2425);
FORCEADD TAP..1
(-2600 2650);
FORCEPROP 3 LASTPIN (-2650 2650) SIG_NAME P3E_CPU0_PE1_PCH_R_RXN<15>
J 0
(-2640 2660);
DISPLAY 0.659574 (-2640 2660);
PAINT MONO (-2640 2660);
DISPLAY INVISIBLE (-2640 2660);
FORCEPROP 1 LASTPIN (-2650 2650) BN 15
J 0
(-2662 2658);
DISPLAY 0.617021 (-2662 2658);
PAINT GREEN (-2662 2658);
FORCEPROP 2 LAST CDS_LIB mstr_standard
J 0
(-2600 2650);
PAINT ORANGE (-2600 2650);
DISPLAY INVISIBLE (-2600 2650);
FORCEPROP 1 LAST PATH I120
J 0
(-2602 2650);
DISPLAY 0.872340 (-2602 2650);
PAINT GREEN (-2602 2650);
DISPLAY INVISIBLE (-2602 2650);
FORCEPROP 1 LAST BODY_TYPE PLUMBING
J 0
(-2600 2700);
DISPLAY 1.170213 (-2600 2700);
PAINT GREEN (-2600 2700);
DISPLAY INVISIBLE (-2600 2700);
FORCEPROP 1 LAST HDL_TAP TRUE
J 0
(-2275 2525);
DISPLAY 1.170213 (-2275 2525);
PAINT ORANGE (-2275 2525);
DISPLAY INVISIBLE (-2275 2525);
FORCEADD TAP..1
(-2725 2000);
FORCEPROP 3 LASTPIN (-2775 2000) SIG_NAME P3E_CPU0_PE1_PCH_R_RXP<8>
J 0
(-2765 2010);
DISPLAY 0.659574 (-2765 2010);
PAINT MONO (-2765 2010);
DISPLAY INVISIBLE (-2765 2010);
FORCEPROP 1 LASTPIN (-2775 2000) BN 8
J 0
(-2787 2008);
DISPLAY 0.617021 (-2787 2008);
PAINT GREEN (-2787 2008);
FORCEPROP 2 LAST CDS_LIB mstr_standard
J 0
(-2725 2000);
PAINT ORANGE (-2725 2000);
DISPLAY INVISIBLE (-2725 2000);
FORCEPROP 1 LAST PATH I121
J 0
(-2727 2000);
DISPLAY 0.872340 (-2727 2000);
PAINT GREEN (-2727 2000);
DISPLAY INVISIBLE (-2727 2000);
FORCEPROP 1 LAST BODY_TYPE PLUMBING
J 0
(-2725 2050);
DISPLAY 1.170213 (-2725 2050);
PAINT GREEN (-2725 2050);
DISPLAY INVISIBLE (-2725 2050);
FORCEPROP 1 LAST HDL_TAP TRUE
J 0
(-2400 1875);
DISPLAY 1.170213 (-2400 1875);
PAINT ORANGE (-2400 1875);
DISPLAY INVISIBLE (-2400 1875);
FORCEADD TAP..1
(-2725 2100);
FORCEPROP 3 LASTPIN (-2775 2100) SIG_NAME P3E_CPU0_PE1_PCH_R_RXP<9>
J 0
(-2765 2110);
DISPLAY 0.659574 (-2765 2110);
PAINT MONO (-2765 2110);
DISPLAY INVISIBLE (-2765 2110);
FORCEPROP 1 LASTPIN (-2775 2100) BN 9
J 0
(-2787 2108);
DISPLAY 0.617021 (-2787 2108);
PAINT GREEN (-2787 2108);
FORCEPROP 2 LAST CDS_LIB mstr_standard
J 0
(-2725 2100);
PAINT ORANGE (-2725 2100);
DISPLAY INVISIBLE (-2725 2100);
FORCEPROP 1 LAST PATH I122
J 0
(-2727 2100);
DISPLAY 0.872340 (-2727 2100);
PAINT GREEN (-2727 2100);
DISPLAY INVISIBLE (-2727 2100);
FORCEPROP 1 LAST BODY_TYPE PLUMBING
J 0
(-2725 2150);
DISPLAY 1.170213 (-2725 2150);
PAINT GREEN (-2725 2150);
DISPLAY INVISIBLE (-2725 2150);
FORCEPROP 1 LAST HDL_TAP TRUE
J 0
(-2400 1975);
DISPLAY 1.170213 (-2400 1975);
PAINT ORANGE (-2400 1975);
DISPLAY INVISIBLE (-2400 1975);
FORCEADD TAP..1
(-2725 2200);
FORCEPROP 3 LASTPIN (-2775 2200) SIG_NAME P3E_CPU0_PE1_PCH_R_RXP<10>
J 0
(-2765 2210);
DISPLAY 0.659574 (-2765 2210);
PAINT MONO (-2765 2210);
DISPLAY INVISIBLE (-2765 2210);
FORCEPROP 1 LASTPIN (-2775 2200) BN 10
J 0
(-2787 2208);
DISPLAY 0.617021 (-2787 2208);
PAINT GREEN (-2787 2208);
FORCEPROP 2 LAST CDS_LIB mstr_standard
J 0
(-2725 2200);
PAINT ORANGE (-2725 2200);
DISPLAY INVISIBLE (-2725 2200);
FORCEPROP 1 LAST PATH I123
J 0
(-2727 2200);
DISPLAY 0.872340 (-2727 2200);
PAINT GREEN (-2727 2200);
DISPLAY INVISIBLE (-2727 2200);
FORCEPROP 1 LAST BODY_TYPE PLUMBING
J 0
(-2725 2250);
DISPLAY 1.170213 (-2725 2250);
PAINT GREEN (-2725 2250);
DISPLAY INVISIBLE (-2725 2250);
FORCEPROP 1 LAST HDL_TAP TRUE
J 0
(-2400 2075);
DISPLAY 1.170213 (-2400 2075);
PAINT ORANGE (-2400 2075);
DISPLAY INVISIBLE (-2400 2075);
FORCEADD TAP..1
(-2725 2300);
FORCEPROP 3 LASTPIN (-2775 2300) SIG_NAME P3E_CPU0_PE1_PCH_R_RXP<11>
J 0
(-2765 2310);
DISPLAY 0.659574 (-2765 2310);
PAINT MONO (-2765 2310);
DISPLAY INVISIBLE (-2765 2310);
FORCEPROP 1 LASTPIN (-2775 2300) BN 11
J 0
(-2787 2308);
DISPLAY 0.617021 (-2787 2308);
PAINT GREEN (-2787 2308);
FORCEPROP 2 LAST CDS_LIB mstr_standard
J 0
(-2725 2300);
PAINT ORANGE (-2725 2300);
DISPLAY INVISIBLE (-2725 2300);
FORCEPROP 1 LAST PATH I124
J 0
(-2727 2300);
DISPLAY 0.872340 (-2727 2300);
PAINT GREEN (-2727 2300);
DISPLAY INVISIBLE (-2727 2300);
FORCEPROP 1 LAST BODY_TYPE PLUMBING
J 0
(-2725 2350);
DISPLAY 1.170213 (-2725 2350);
PAINT GREEN (-2725 2350);
DISPLAY INVISIBLE (-2725 2350);
FORCEPROP 1 LAST HDL_TAP TRUE
J 0
(-2400 2175);
DISPLAY 1.170213 (-2400 2175);
PAINT ORANGE (-2400 2175);
DISPLAY INVISIBLE (-2400 2175);
FORCEADD TAP..1
(-2725 2400);
FORCEPROP 3 LASTPIN (-2775 2400) SIG_NAME P3E_CPU0_PE1_PCH_R_RXP<12>
J 0
(-2765 2410);
DISPLAY 0.659574 (-2765 2410);
PAINT MONO (-2765 2410);
DISPLAY INVISIBLE (-2765 2410);
FORCEPROP 1 LASTPIN (-2775 2400) BN 12
J 0
(-2787 2408);
DISPLAY 0.617021 (-2787 2408);
PAINT GREEN (-2787 2408);
FORCEPROP 2 LAST CDS_LIB mstr_standard
J 0
(-2725 2400);
PAINT ORANGE (-2725 2400);
DISPLAY INVISIBLE (-2725 2400);
FORCEPROP 1 LAST PATH I125
J 0
(-2727 2400);
DISPLAY 0.872340 (-2727 2400);
PAINT GREEN (-2727 2400);
DISPLAY INVISIBLE (-2727 2400);
FORCEPROP 1 LAST BODY_TYPE PLUMBING
J 0
(-2725 2450);
DISPLAY 1.170213 (-2725 2450);
PAINT GREEN (-2725 2450);
DISPLAY INVISIBLE (-2725 2450);
FORCEPROP 1 LAST HDL_TAP TRUE
J 0
(-2400 2275);
DISPLAY 1.170213 (-2400 2275);
PAINT ORANGE (-2400 2275);
DISPLAY INVISIBLE (-2400 2275);
FORCEADD TAP..1
(-2725 2500);
FORCEPROP 3 LASTPIN (-2775 2500) SIG_NAME P3E_CPU0_PE1_PCH_R_RXP<13>
J 0
(-2765 2510);
DISPLAY 0.659574 (-2765 2510);
PAINT MONO (-2765 2510);
DISPLAY INVISIBLE (-2765 2510);
FORCEPROP 1 LASTPIN (-2775 2500) BN 13
J 0
(-2787 2508);
DISPLAY 0.617021 (-2787 2508);
PAINT GREEN (-2787 2508);
FORCEPROP 2 LAST CDS_LIB mstr_standard
J 0
(-2725 2500);
PAINT ORANGE (-2725 2500);
DISPLAY INVISIBLE (-2725 2500);
FORCEPROP 1 LAST PATH I126
J 0
(-2727 2500);
DISPLAY 0.872340 (-2727 2500);
PAINT GREEN (-2727 2500);
DISPLAY INVISIBLE (-2727 2500);
FORCEPROP 1 LAST BODY_TYPE PLUMBING
J 0
(-2725 2550);
DISPLAY 1.170213 (-2725 2550);
PAINT GREEN (-2725 2550);
DISPLAY INVISIBLE (-2725 2550);
FORCEPROP 1 LAST HDL_TAP TRUE
J 0
(-2400 2375);
DISPLAY 1.170213 (-2400 2375);
PAINT ORANGE (-2400 2375);
DISPLAY INVISIBLE (-2400 2375);
FORCEADD TAP..1
(-2725 2600);
FORCEPROP 3 LASTPIN (-2775 2600) SIG_NAME P3E_CPU0_PE1_PCH_R_RXP<14>
J 0
(-2765 2610);
DISPLAY 0.659574 (-2765 2610);
PAINT MONO (-2765 2610);
DISPLAY INVISIBLE (-2765 2610);
FORCEPROP 1 LASTPIN (-2775 2600) BN 14
J 0
(-2787 2608);
DISPLAY 0.617021 (-2787 2608);
PAINT GREEN (-2787 2608);
FORCEPROP 2 LAST CDS_LIB mstr_standard
J 0
(-2725 2600);
PAINT ORANGE (-2725 2600);
DISPLAY INVISIBLE (-2725 2600);
FORCEPROP 1 LAST PATH I127
J 0
(-2727 2600);
DISPLAY 0.872340 (-2727 2600);
PAINT GREEN (-2727 2600);
DISPLAY INVISIBLE (-2727 2600);
FORCEPROP 1 LAST BODY_TYPE PLUMBING
J 0
(-2725 2650);
DISPLAY 1.170213 (-2725 2650);
PAINT GREEN (-2725 2650);
DISPLAY INVISIBLE (-2725 2650);
FORCEPROP 1 LAST HDL_TAP TRUE
J 0
(-2400 2475);
DISPLAY 1.170213 (-2400 2475);
PAINT ORANGE (-2400 2475);
DISPLAY INVISIBLE (-2400 2475);
FORCEADD TAP..1
(-2725 2700);
FORCEPROP 3 LASTPIN (-2775 2700) SIG_NAME P3E_CPU0_PE1_PCH_R_RXP<15>
J 0
(-2765 2710);
DISPLAY 0.659574 (-2765 2710);
PAINT MONO (-2765 2710);
DISPLAY INVISIBLE (-2765 2710);
FORCEPROP 1 LASTPIN (-2775 2700) BN 15
J 0
(-2787 2708);
DISPLAY 0.617021 (-2787 2708);
PAINT GREEN (-2787 2708);
FORCEPROP 2 LAST CDS_LIB mstr_standard
J 0
(-2725 2700);
PAINT ORANGE (-2725 2700);
DISPLAY INVISIBLE (-2725 2700);
FORCEPROP 1 LAST PATH I128
J 0
(-2727 2700);
DISPLAY 0.872340 (-2727 2700);
PAINT GREEN (-2727 2700);
DISPLAY INVISIBLE (-2727 2700);
FORCEPROP 1 LAST BODY_TYPE PLUMBING
J 0
(-2725 2750);
DISPLAY 1.170213 (-2725 2750);
PAINT GREEN (-2725 2750);
DISPLAY INVISIBLE (-2725 2750);
FORCEPROP 1 LAST HDL_TAP TRUE
J 0
(-2400 2575);
DISPLAY 1.170213 (-2400 2575);
PAINT ORANGE (-2400 2575);
DISPLAY INVISIBLE (-2400 2575);
FORCEADD OFFPAGE..1
(-6700 2025);
FORCEPROP 2 LAST $XR0 105 
J 0
(-6952 2025);
DISPLAY 0.638298 (-6952 2025);
PAINT MONO (-6952 2025);
FORCEPROP 2 LAST CDS_LIB mstr_standard
J 0
(-6700 2025);
PAINT ORANGE (-6700 2025);
DISPLAY INVISIBLE (-6700 2025);
FORCEPROP 2 LAST PATH I129
J 0
(-6650 2100);
DISPLAY 1.021277 (-6650 2100);
PAINT ORANGE (-6650 2100);
DISPLAY INVISIBLE (-6650 2100);
FORCEPROP 1 LAST OFFPAGE TRUE
J 0
(-6375 1900);
DISPLAY 0.872340 (-6375 1900);
PAINT GREEN (-6375 1900);
DISPLAY INVISIBLE (-6375 1900);
FORCEPROP 1 LAST COMMENT_BODY TRUE
J 0
(-6575 1925);
DISPLAY 0.872340 (-6575 1925);
PAINT GREEN (-6575 1925);
DISPLAY INVISIBLE (-6575 1925);
FORCEADD OFFPAGE..1
(-6700 1925);
FORCEPROP 2 LAST $XR0 105 
J 0
(-6952 1925);
DISPLAY 0.638298 (-6952 1925);
PAINT MONO (-6952 1925);
FORCEPROP 2 LAST CDS_LIB mstr_standard
J 0
(-6700 1925);
PAINT ORANGE (-6700 1925);
DISPLAY INVISIBLE (-6700 1925);
FORCEPROP 2 LAST PATH I130
J 0
(-6650 2000);
DISPLAY 1.021277 (-6650 2000);
PAINT ORANGE (-6650 2000);
DISPLAY INVISIBLE (-6650 2000);
FORCEPROP 1 LAST OFFPAGE TRUE
J 0
(-6375 1800);
DISPLAY 0.872340 (-6375 1800);
PAINT GREEN (-6375 1800);
DISPLAY INVISIBLE (-6375 1800);
FORCEPROP 1 LAST COMMENT_BODY TRUE
J 0
(-6575 1825);
DISPLAY 0.872340 (-6575 1825);
PAINT GREEN (-6575 1825);
DISPLAY INVISIBLE (-6575 1825);
FORCEADD OFFPAGE..2
(-1375 2025);
FORCEPROP 2 LAST $XR0 105 
J 0
(-1186 2025);
DISPLAY 0.638298 (-1186 2025);
PAINT MONO (-1186 2025);
FORCEPROP 2 LAST CDS_LIB mstr_standard
J 0
(-1375 2025);
PAINT ORANGE (-1375 2025);
DISPLAY INVISIBLE (-1375 2025);
FORCEPROP 2 LAST PATH I131
J 0
(-1200 2100);
DISPLAY 1.021277 (-1200 2100);
PAINT ORANGE (-1200 2100);
DISPLAY INVISIBLE (-1200 2100);
FORCEPROP 1 LAST OFFPAGE TRUE
J 0
(-1050 1900);
DISPLAY 0.872340 (-1050 1900);
PAINT GREEN (-1050 1900);
DISPLAY INVISIBLE (-1050 1900);
FORCEPROP 1 LAST COMMENT_BODY TRUE
J 0
(-1420 1930);
DISPLAY 0.872340 (-1420 1930);
PAINT GREEN (-1420 1930);
DISPLAY INVISIBLE (-1420 1930);
FORCEADD OFFPAGE..2
(-1350 1950);
FORCEPROP 2 LAST $XR0 105 
J 0
(-1161 1950);
DISPLAY 0.638298 (-1161 1950);
PAINT MONO (-1161 1950);
FORCEPROP 2 LAST CDS_LIB mstr_standard
J 0
(-1350 1950);
PAINT ORANGE (-1350 1950);
DISPLAY INVISIBLE (-1350 1950);
FORCEPROP 2 LAST PATH I132
J 0
(-1175 2025);
DISPLAY 1.021277 (-1175 2025);
PAINT ORANGE (-1175 2025);
DISPLAY INVISIBLE (-1175 2025);
FORCEPROP 1 LAST OFFPAGE TRUE
J 0
(-1025 1825);
DISPLAY 0.872340 (-1025 1825);
PAINT GREEN (-1025 1825);
DISPLAY INVISIBLE (-1025 1825);
FORCEPROP 1 LAST COMMENT_BODY TRUE
J 0
(-1395 1855);
DISPLAY 0.872340 (-1395 1855);
PAINT GREEN (-1395 1855);
DISPLAY INVISIBLE (-1395 1855);
FORCEADD TAP..6
(-5625 2300);
FORCEPROP 3 LASTPIN (-5575 2300) SIG_NAME P3E_CPU0_PE1_PCH_C_TXP<11>
J 0
(-5565 2310);
DISPLAY 0.659574 (-5565 2310);
PAINT MONO (-5565 2310);
DISPLAY INVISIBLE (-5565 2310);
FORCEPROP 1 LASTPIN (-5575 2300) BN 11
J 0
(-5627 2308);
DISPLAY 0.617021 (-5627 2308);
PAINT GREEN (-5627 2308);
FORCEPROP 2 LAST CDS_LIB mstr_standard
J 0
(-5625 2300);
PAINT ORANGE (-5625 2300);
DISPLAY INVISIBLE (-5625 2300);
FORCEPROP 1 LAST PATH I133
J 0
(-5627 2300);
DISPLAY 0.872340 (-5627 2300);
PAINT GREEN (-5627 2300);
DISPLAY INVISIBLE (-5627 2300);
FORCEPROP 1 LAST BODY_TYPE PLUMBING
J 0
(-5625 2250);
DISPLAY 1.170213 (-5625 2250);
PAINT GREEN (-5625 2250);
DISPLAY INVISIBLE (-5625 2250);
FORCEPROP 1 LAST HDL_TAP TRUE
J 0
(-5300 2175);
DISPLAY 1.170213 (-5300 2175);
PAINT ORANGE (-5300 2175);
DISPLAY INVISIBLE (-5300 2175);
FORCEADD TAP..6
(-5500 2250);
FORCEPROP 3 LASTPIN (-5450 2250) SIG_NAME P3E_CPU0_PE1_PCH_C_TXN<11>
J 0
(-5440 2260);
DISPLAY 0.659574 (-5440 2260);
PAINT MONO (-5440 2260);
DISPLAY INVISIBLE (-5440 2260);
FORCEPROP 1 LASTPIN (-5450 2250) BN 11
J 0
(-5502 2258);
DISPLAY 0.617021 (-5502 2258);
PAINT GREEN (-5502 2258);
FORCEPROP 2 LAST CDS_LIB mstr_standard
J 0
(-5500 2250);
PAINT ORANGE (-5500 2250);
DISPLAY INVISIBLE (-5500 2250);
FORCEPROP 1 LAST PATH I134
J 0
(-5502 2250);
DISPLAY 0.872340 (-5502 2250);
PAINT GREEN (-5502 2250);
DISPLAY INVISIBLE (-5502 2250);
FORCEPROP 1 LAST BODY_TYPE PLUMBING
J 0
(-5500 2200);
DISPLAY 1.170213 (-5500 2200);
PAINT GREEN (-5500 2200);
DISPLAY INVISIBLE (-5500 2200);
FORCEPROP 1 LAST HDL_TAP TRUE
J 0
(-5175 2125);
DISPLAY 1.170213 (-5175 2125);
PAINT ORANGE (-5175 2125);
DISPLAY INVISIBLE (-5175 2125);
FORCEADD OFFPAGE..1
(-6500 3350);
FORCEPROP 2 LAST $XR0 129 
J 0
(-6752 3350);
DISPLAY 0.638298 (-6752 3350);
PAINT MONO (-6752 3350);
FORCEPROP 2 LAST CDS_LIB mstr_standard
J 0
(-6500 3350);
PAINT ORANGE (-6500 3350);
DISPLAY INVISIBLE (-6500 3350);
FORCEPROP 2 LAST PATH I18
J 0
(-6450 3425);
DISPLAY 1.021277 (-6450 3425);
PAINT ORANGE (-6450 3425);
DISPLAY INVISIBLE (-6450 3425);
FORCEPROP 1 LAST OFFPAGE TRUE
J 0
(-6175 3225);
DISPLAY 1.170213 (-6175 3225);
PAINT GREEN (-6175 3225);
DISPLAY INVISIBLE (-6175 3225);
FORCEPROP 1 LAST COMMENT_BODY TRUE
J 0
(-6375 3250);
DISPLAY 1.170213 (-6375 3250);
PAINT PEACH (-6375 3250);
DISPLAY INVISIBLE (-6375 3250);
FORCEADD OFFPAGE..1
(-6500 3250);
FORCEPROP 2 LAST $XR0 129 
J 0
(-6752 3250);
DISPLAY 0.638298 (-6752 3250);
PAINT MONO (-6752 3250);
FORCEPROP 2 LAST CDS_LIB mstr_standard
J 0
(-6500 3250);
PAINT ORANGE (-6500 3250);
DISPLAY INVISIBLE (-6500 3250);
FORCEPROP 2 LAST PATH I19
J 0
(-6450 3325);
DISPLAY 1.021277 (-6450 3325);
PAINT ORANGE (-6450 3325);
DISPLAY INVISIBLE (-6450 3325);
FORCEPROP 1 LAST OFFPAGE TRUE
J 0
(-6175 3125);
DISPLAY 1.170213 (-6175 3125);
PAINT GREEN (-6175 3125);
DISPLAY INVISIBLE (-6175 3125);
FORCEPROP 1 LAST COMMENT_BODY TRUE
J 0
(-6375 3150);
DISPLAY 1.170213 (-6375 3150);
PAINT PEACH (-6375 3150);
DISPLAY INVISIBLE (-6375 3150);
FORCEADD TAP..1
R 2
(-5425 3150);
FORCEPROP 3 LASTPIN (-5375 3150) SIG_NAME DMI_CPU0_PCH_TX_C_DP<3>
J 0
(-5365 3160);
DISPLAY 0.659574 (-5365 3160);
PAINT MONO (-5365 3160);
DISPLAY INVISIBLE (-5365 3160);
FORCEPROP 1 LASTPIN (-5375 3150) BN 3
J 2
(-5363 3158);
DISPLAY 0.617021 (-5363 3158);
PAINT VIOLET (-5363 3158);
FORCEPROP 2 LAST BOM_COST SB
J 0
(-5450 3200);
DISPLAY 0.744681 (-5450 3200);
PAINT MONO (-5450 3200);
DISPLAY INVISIBLE (-5450 3200);
FORCEPROP 2 LAST CDS_LIB mstr_standard
J 0
(-5425 3150);
PAINT ORANGE (-5425 3150);
DISPLAY INVISIBLE (-5425 3150);
FORCEPROP 1 LAST PATH I21
J 2
(-5423 3150);
DISPLAY 0.872340 (-5423 3150);
PAINT GREEN (-5423 3150);
DISPLAY INVISIBLE (-5423 3150);
FORCEPROP 1 LAST BODY_TYPE PLUMBING
J 2
(-5425 3200);
DISPLAY 1.085106 (-5425 3200);
PAINT GREEN (-5425 3200);
DISPLAY INVISIBLE (-5425 3200);
FORCEPROP 1 LAST HDL_TAP TRUE
J 2
(-5750 3025);
DISPLAY 1.085106 (-5750 3025);
PAINT GREEN (-5750 3025);
DISPLAY INVISIBLE (-5750 3025);
FORCEADD TAP..1
R 2
(-5425 3050);
FORCEPROP 3 LASTPIN (-5375 3050) SIG_NAME DMI_CPU0_PCH_TX_C_DP<2>
J 0
(-5365 3060);
DISPLAY 0.659574 (-5365 3060);
PAINT MONO (-5365 3060);
DISPLAY INVISIBLE (-5365 3060);
FORCEPROP 1 LASTPIN (-5375 3050) BN 2
J 2
(-5363 3058);
DISPLAY 0.617021 (-5363 3058);
PAINT VIOLET (-5363 3058);
FORCEPROP 2 LAST BOM_COST SB
J 0
(-5450 3100);
DISPLAY 0.744681 (-5450 3100);
PAINT MONO (-5450 3100);
DISPLAY INVISIBLE (-5450 3100);
FORCEPROP 2 LAST CDS_LIB mstr_standard
J 0
(-5425 3050);
PAINT ORANGE (-5425 3050);
DISPLAY INVISIBLE (-5425 3050);
FORCEPROP 1 LAST PATH I22
J 2
(-5423 3050);
DISPLAY 0.872340 (-5423 3050);
PAINT GREEN (-5423 3050);
DISPLAY INVISIBLE (-5423 3050);
FORCEPROP 1 LAST BODY_TYPE PLUMBING
J 2
(-5425 3100);
DISPLAY 1.085106 (-5425 3100);
PAINT GREEN (-5425 3100);
DISPLAY INVISIBLE (-5425 3100);
FORCEPROP 1 LAST HDL_TAP TRUE
J 2
(-5750 2925);
DISPLAY 1.085106 (-5750 2925);
PAINT GREEN (-5750 2925);
DISPLAY INVISIBLE (-5750 2925);
FORCEADD TAP..1
R 2
(-5425 2950);
FORCEPROP 3 LASTPIN (-5375 2950) SIG_NAME DMI_CPU0_PCH_TX_C_DP<1>
J 0
(-5365 2960);
DISPLAY 0.659574 (-5365 2960);
PAINT MONO (-5365 2960);
DISPLAY INVISIBLE (-5365 2960);
FORCEPROP 1 LASTPIN (-5375 2950) BN 1
J 2
(-5363 2958);
DISPLAY 0.617021 (-5363 2958);
PAINT VIOLET (-5363 2958);
FORCEPROP 2 LAST CDS_LIB mstr_standard
J 0
(-5425 2950);
PAINT ORANGE (-5425 2950);
DISPLAY INVISIBLE (-5425 2950);
FORCEPROP 2 LAST BOM_COST SB
J 0
(-5450 3000);
DISPLAY 0.744681 (-5450 3000);
PAINT MONO (-5450 3000);
DISPLAY INVISIBLE (-5450 3000);
FORCEPROP 1 LAST PATH I23
J 2
(-5423 2950);
DISPLAY 0.872340 (-5423 2950);
PAINT GREEN (-5423 2950);
DISPLAY INVISIBLE (-5423 2950);
FORCEPROP 1 LAST BODY_TYPE PLUMBING
J 2
(-5425 3000);
DISPLAY 1.085106 (-5425 3000);
PAINT GREEN (-5425 3000);
DISPLAY INVISIBLE (-5425 3000);
FORCEPROP 1 LAST HDL_TAP TRUE
J 2
(-5750 2825);
DISPLAY 1.085106 (-5750 2825);
PAINT GREEN (-5750 2825);
DISPLAY INVISIBLE (-5750 2825);
FORCEADD TAP..1
R 2
(-5425 2850);
FORCEPROP 3 LASTPIN (-5375 2850) SIG_NAME DMI_CPU0_PCH_TX_C_DP<0>
J 0
(-5365 2860);
DISPLAY 0.659574 (-5365 2860);
PAINT MONO (-5365 2860);
DISPLAY INVISIBLE (-5365 2860);
FORCEPROP 1 LASTPIN (-5375 2850) BN 0
J 2
(-5363 2858);
DISPLAY 0.617021 (-5363 2858);
PAINT VIOLET (-5363 2858);
FORCEPROP 2 LAST CDS_LIB mstr_standard
J 0
(-5425 2850);
PAINT ORANGE (-5425 2850);
DISPLAY INVISIBLE (-5425 2850);
FORCEPROP 2 LAST BOM_COST SB
J 0
(-5450 2900);
DISPLAY 0.744681 (-5450 2900);
PAINT MONO (-5450 2900);
DISPLAY INVISIBLE (-5450 2900);
FORCEPROP 1 LAST PATH I24
J 2
(-5423 2850);
DISPLAY 0.872340 (-5423 2850);
PAINT GREEN (-5423 2850);
DISPLAY INVISIBLE (-5423 2850);
FORCEPROP 1 LAST BODY_TYPE PLUMBING
J 2
(-5425 2900);
DISPLAY 1.085106 (-5425 2900);
PAINT GREEN (-5425 2900);
DISPLAY INVISIBLE (-5425 2900);
FORCEPROP 1 LAST HDL_TAP TRUE
J 2
(-5750 2725);
DISPLAY 1.085106 (-5750 2725);
PAINT GREEN (-5750 2725);
DISPLAY INVISIBLE (-5750 2725);
FORCEADD TAP..1
R 2
(-5575 3100);
FORCEPROP 3 LASTPIN (-5525 3100) SIG_NAME DMI_CPU0_PCH_TX_C_DN<3>
J 0
(-5515 3110);
DISPLAY 0.659574 (-5515 3110);
PAINT MONO (-5515 3110);
DISPLAY INVISIBLE (-5515 3110);
FORCEPROP 1 LASTPIN (-5525 3100) BN 3
J 2
(-5513 3108);
DISPLAY 0.617021 (-5513 3108);
PAINT VIOLET (-5513 3108);
FORCEPROP 2 LAST BOM_COST SB
J 0
(-5600 3150);
DISPLAY 0.744681 (-5600 3150);
PAINT MONO (-5600 3150);
DISPLAY INVISIBLE (-5600 3150);
FORCEPROP 2 LAST CDS_LIB mstr_standard
J 0
(-5575 3100);
PAINT ORANGE (-5575 3100);
DISPLAY INVISIBLE (-5575 3100);
FORCEPROP 1 LAST PATH I25
J 2
(-5573 3100);
DISPLAY 0.872340 (-5573 3100);
PAINT GREEN (-5573 3100);
DISPLAY INVISIBLE (-5573 3100);
FORCEPROP 1 LAST BODY_TYPE PLUMBING
J 2
(-5575 3150);
DISPLAY 1.085106 (-5575 3150);
PAINT GREEN (-5575 3150);
DISPLAY INVISIBLE (-5575 3150);
FORCEPROP 1 LAST HDL_TAP TRUE
J 2
(-5900 2975);
DISPLAY 1.085106 (-5900 2975);
PAINT GREEN (-5900 2975);
DISPLAY INVISIBLE (-5900 2975);
FORCEADD TAP..1
R 2
(-5575 3000);
FORCEPROP 3 LASTPIN (-5525 3000) SIG_NAME DMI_CPU0_PCH_TX_C_DN<2>
J 0
(-5515 3010);
DISPLAY 0.659574 (-5515 3010);
PAINT MONO (-5515 3010);
DISPLAY INVISIBLE (-5515 3010);
FORCEPROP 1 LASTPIN (-5525 3000) BN 2
J 2
(-5513 3008);
DISPLAY 0.617021 (-5513 3008);
PAINT VIOLET (-5513 3008);
FORCEPROP 2 LAST BOM_COST SB
J 0
(-5600 3050);
DISPLAY 0.744681 (-5600 3050);
PAINT MONO (-5600 3050);
DISPLAY INVISIBLE (-5600 3050);
FORCEPROP 2 LAST CDS_LIB mstr_standard
J 0
(-5575 3000);
PAINT ORANGE (-5575 3000);
DISPLAY INVISIBLE (-5575 3000);
FORCEPROP 1 LAST PATH I26
J 2
(-5573 3000);
DISPLAY 0.872340 (-5573 3000);
PAINT GREEN (-5573 3000);
DISPLAY INVISIBLE (-5573 3000);
FORCEPROP 1 LAST BODY_TYPE PLUMBING
J 2
(-5575 3050);
DISPLAY 1.085106 (-5575 3050);
PAINT GREEN (-5575 3050);
DISPLAY INVISIBLE (-5575 3050);
FORCEPROP 1 LAST HDL_TAP TRUE
J 2
(-5900 2875);
DISPLAY 1.085106 (-5900 2875);
PAINT GREEN (-5900 2875);
DISPLAY INVISIBLE (-5900 2875);
FORCEADD TAP..1
R 2
(-5575 2900);
FORCEPROP 3 LASTPIN (-5525 2900) SIG_NAME DMI_CPU0_PCH_TX_C_DN<1>
J 0
(-5515 2910);
DISPLAY 0.659574 (-5515 2910);
PAINT MONO (-5515 2910);
DISPLAY INVISIBLE (-5515 2910);
FORCEPROP 1 LASTPIN (-5525 2900) BN 1
J 2
(-5513 2908);
DISPLAY 0.617021 (-5513 2908);
PAINT VIOLET (-5513 2908);
FORCEPROP 2 LAST BOM_COST SB
J 0
(-5600 2950);
DISPLAY 0.744681 (-5600 2950);
PAINT MONO (-5600 2950);
DISPLAY INVISIBLE (-5600 2950);
FORCEPROP 2 LAST CDS_LIB mstr_standard
J 0
(-5575 2900);
PAINT ORANGE (-5575 2900);
DISPLAY INVISIBLE (-5575 2900);
FORCEPROP 1 LAST PATH I27
J 2
(-5573 2900);
DISPLAY 0.872340 (-5573 2900);
PAINT GREEN (-5573 2900);
DISPLAY INVISIBLE (-5573 2900);
FORCEPROP 1 LAST BODY_TYPE PLUMBING
J 2
(-5575 2950);
DISPLAY 1.085106 (-5575 2950);
PAINT GREEN (-5575 2950);
DISPLAY INVISIBLE (-5575 2950);
FORCEPROP 1 LAST HDL_TAP TRUE
J 2
(-5900 2775);
DISPLAY 1.085106 (-5900 2775);
PAINT GREEN (-5900 2775);
DISPLAY INVISIBLE (-5900 2775);
FORCEADD TAP..1
R 2
(-5575 2800);
FORCEPROP 3 LASTPIN (-5525 2800) SIG_NAME DMI_CPU0_PCH_TX_C_DN<0>
J 0
(-5515 2810);
DISPLAY 0.659574 (-5515 2810);
PAINT MONO (-5515 2810);
DISPLAY INVISIBLE (-5515 2810);
FORCEPROP 1 LASTPIN (-5525 2800) BN 0
J 2
(-5513 2808);
DISPLAY 0.617021 (-5513 2808);
PAINT VIOLET (-5513 2808);
FORCEPROP 2 LAST BOM_COST SB
J 0
(-5600 2850);
DISPLAY 0.744681 (-5600 2850);
PAINT MONO (-5600 2850);
DISPLAY INVISIBLE (-5600 2850);
FORCEPROP 2 LAST CDS_LIB mstr_standard
J 0
(-5575 2800);
PAINT ORANGE (-5575 2800);
DISPLAY INVISIBLE (-5575 2800);
FORCEPROP 1 LAST PATH I28
J 2
(-5573 2800);
DISPLAY 0.872340 (-5573 2800);
PAINT GREEN (-5573 2800);
DISPLAY INVISIBLE (-5573 2800);
FORCEPROP 1 LAST BODY_TYPE PLUMBING
J 2
(-5575 2850);
DISPLAY 1.085106 (-5575 2850);
PAINT GREEN (-5575 2850);
DISPLAY INVISIBLE (-5575 2850);
FORCEPROP 1 LAST HDL_TAP TRUE
J 2
(-5900 2675);
DISPLAY 1.085106 (-5900 2675);
PAINT GREEN (-5900 2675);
DISPLAY INVISIBLE (-5900 2675);
FORCEADD TAP..6
R 2
(-2725 3150);
FORCEPROP 3 LASTPIN (-2775 3150) SIG_NAME DMI_CPU0_PCH_RX_DP<3>
J 0
(-2765 3160);
DISPLAY 0.659574 (-2765 3160);
PAINT MONO (-2765 3160);
DISPLAY INVISIBLE (-2765 3160);
FORCEPROP 1 LASTPIN (-2775 3150) BN 3
J 2
(-2723 3158);
DISPLAY 0.617021 (-2723 3158);
PAINT VIOLET (-2723 3158);
FORCEPROP 2 LAST BOM_COST SB
J 0
(-2750 3200);
DISPLAY 0.744681 (-2750 3200);
PAINT MONO (-2750 3200);
DISPLAY INVISIBLE (-2750 3200);
FORCEPROP 2 LAST CDS_LIB mstr_standard
J 0
(-2725 3150);
PAINT ORANGE (-2725 3150);
DISPLAY INVISIBLE (-2725 3150);
FORCEPROP 1 LAST PATH I29
J 2
(-2723 3150);
DISPLAY 0.872340 (-2723 3150);
PAINT GREEN (-2723 3150);
DISPLAY INVISIBLE (-2723 3150);
FORCEPROP 1 LAST BODY_TYPE PLUMBING
J 2
(-2725 3100);
DISPLAY 0.872340 (-2725 3100);
PAINT GREEN (-2725 3100);
DISPLAY INVISIBLE (-2725 3100);
FORCEPROP 1 LAST HDL_TAP TRUE
J 2
(-3050 3025);
DISPLAY 0.872340 (-3050 3025);
PAINT GREEN (-3050 3025);
DISPLAY INVISIBLE (-3050 3025);
FORCEADD TAP..6
R 2
(-2600 3100);
FORCEPROP 3 LASTPIN (-2650 3100) SIG_NAME DMI_CPU0_PCH_RX_DN<3>
J 0
(-2640 3110);
DISPLAY 0.659574 (-2640 3110);
PAINT MONO (-2640 3110);
DISPLAY INVISIBLE (-2640 3110);
FORCEPROP 1 LASTPIN (-2650 3100) BN 3
J 2
(-2598 3108);
DISPLAY 0.617021 (-2598 3108);
PAINT VIOLET (-2598 3108);
FORCEPROP 2 LAST BOM_COST SB
J 0
(-2625 3150);
DISPLAY 0.744681 (-2625 3150);
PAINT MONO (-2625 3150);
DISPLAY INVISIBLE (-2625 3150);
FORCEPROP 2 LAST CDS_LIB mstr_standard
J 0
(-2600 3100);
PAINT ORANGE (-2600 3100);
DISPLAY INVISIBLE (-2600 3100);
FORCEPROP 1 LAST PATH I30
J 2
(-2598 3100);
DISPLAY 0.872340 (-2598 3100);
PAINT GREEN (-2598 3100);
DISPLAY INVISIBLE (-2598 3100);
FORCEPROP 1 LAST BODY_TYPE PLUMBING
J 2
(-2600 3050);
DISPLAY 0.872340 (-2600 3050);
PAINT GREEN (-2600 3050);
DISPLAY INVISIBLE (-2600 3050);
FORCEPROP 1 LAST HDL_TAP TRUE
J 2
(-2925 2975);
DISPLAY 0.872340 (-2925 2975);
PAINT GREEN (-2925 2975);
DISPLAY INVISIBLE (-2925 2975);
FORCEADD TAP..6
R 2
(-2725 3050);
FORCEPROP 3 LASTPIN (-2775 3050) SIG_NAME DMI_CPU0_PCH_RX_DP<2>
J 0
(-2765 3060);
DISPLAY 0.659574 (-2765 3060);
PAINT MONO (-2765 3060);
DISPLAY INVISIBLE (-2765 3060);
FORCEPROP 1 LASTPIN (-2775 3050) BN 2
J 2
(-2723 3058);
DISPLAY 0.617021 (-2723 3058);
PAINT VIOLET (-2723 3058);
FORCEPROP 2 LAST BOM_COST SB
J 0
(-2750 3100);
DISPLAY 0.744681 (-2750 3100);
PAINT MONO (-2750 3100);
DISPLAY INVISIBLE (-2750 3100);
FORCEPROP 2 LAST CDS_LIB mstr_standard
J 0
(-2725 3050);
PAINT ORANGE (-2725 3050);
DISPLAY INVISIBLE (-2725 3050);
FORCEPROP 1 LAST PATH I31
J 2
(-2723 3050);
DISPLAY 0.872340 (-2723 3050);
PAINT GREEN (-2723 3050);
DISPLAY INVISIBLE (-2723 3050);
FORCEPROP 1 LAST BODY_TYPE PLUMBING
J 2
(-2725 3000);
DISPLAY 0.872340 (-2725 3000);
PAINT GREEN (-2725 3000);
DISPLAY INVISIBLE (-2725 3000);
FORCEPROP 1 LAST HDL_TAP TRUE
J 2
(-3050 2925);
DISPLAY 0.872340 (-3050 2925);
PAINT GREEN (-3050 2925);
DISPLAY INVISIBLE (-3050 2925);
FORCEADD TAP..6
R 2
(-2725 2950);
FORCEPROP 3 LASTPIN (-2775 2950) SIG_NAME DMI_CPU0_PCH_RX_DP<1>
J 0
(-2765 2960);
DISPLAY 0.659574 (-2765 2960);
PAINT MONO (-2765 2960);
DISPLAY INVISIBLE (-2765 2960);
FORCEPROP 1 LASTPIN (-2775 2950) BN 1
J 2
(-2723 2958);
DISPLAY 0.617021 (-2723 2958);
PAINT VIOLET (-2723 2958);
FORCEPROP 2 LAST BOM_COST SB
J 0
(-2750 3000);
DISPLAY 0.744681 (-2750 3000);
PAINT MONO (-2750 3000);
DISPLAY INVISIBLE (-2750 3000);
FORCEPROP 2 LAST CDS_LIB mstr_standard
J 0
(-2725 2950);
PAINT ORANGE (-2725 2950);
DISPLAY INVISIBLE (-2725 2950);
FORCEPROP 1 LAST PATH I32
J 2
(-2723 2950);
DISPLAY 0.872340 (-2723 2950);
PAINT GREEN (-2723 2950);
DISPLAY INVISIBLE (-2723 2950);
FORCEPROP 1 LAST BODY_TYPE PLUMBING
J 2
(-2725 2900);
DISPLAY 0.872340 (-2725 2900);
PAINT GREEN (-2725 2900);
DISPLAY INVISIBLE (-2725 2900);
FORCEPROP 1 LAST HDL_TAP TRUE
J 2
(-3050 2825);
DISPLAY 0.872340 (-3050 2825);
PAINT GREEN (-3050 2825);
DISPLAY INVISIBLE (-3050 2825);
FORCEADD TAP..6
R 2
(-2725 2850);
FORCEPROP 3 LASTPIN (-2775 2850) SIG_NAME DMI_CPU0_PCH_RX_DP<0>
J 0
(-2765 2860);
DISPLAY 0.659574 (-2765 2860);
PAINT MONO (-2765 2860);
DISPLAY INVISIBLE (-2765 2860);
FORCEPROP 1 LASTPIN (-2775 2850) BN 0
J 2
(-2723 2858);
DISPLAY 0.617021 (-2723 2858);
PAINT VIOLET (-2723 2858);
FORCEPROP 2 LAST CDS_LIB mstr_standard
J 0
(-2725 2850);
PAINT ORANGE (-2725 2850);
DISPLAY INVISIBLE (-2725 2850);
FORCEPROP 2 LAST BOM_COST SB
J 0
(-2750 2900);
DISPLAY 0.744681 (-2750 2900);
PAINT MONO (-2750 2900);
DISPLAY INVISIBLE (-2750 2900);
FORCEPROP 1 LAST PATH I33
J 2
(-2723 2850);
DISPLAY 0.872340 (-2723 2850);
PAINT GREEN (-2723 2850);
DISPLAY INVISIBLE (-2723 2850);
FORCEPROP 1 LAST BODY_TYPE PLUMBING
J 2
(-2725 2800);
DISPLAY 0.872340 (-2725 2800);
PAINT GREEN (-2725 2800);
DISPLAY INVISIBLE (-2725 2800);
FORCEPROP 1 LAST HDL_TAP TRUE
J 2
(-3050 2725);
DISPLAY 0.872340 (-3050 2725);
PAINT GREEN (-3050 2725);
DISPLAY INVISIBLE (-3050 2725);
FORCEADD TAP..6
R 2
(-2600 3000);
FORCEPROP 3 LASTPIN (-2650 3000) SIG_NAME DMI_CPU0_PCH_RX_DN<2>
J 0
(-2640 3010);
DISPLAY 0.659574 (-2640 3010);
PAINT MONO (-2640 3010);
DISPLAY INVISIBLE (-2640 3010);
FORCEPROP 1 LASTPIN (-2650 3000) BN 2
J 2
(-2598 3008);
DISPLAY 0.617021 (-2598 3008);
PAINT VIOLET (-2598 3008);
FORCEPROP 2 LAST BOM_COST SB
J 0
(-2625 3050);
DISPLAY 0.744681 (-2625 3050);
PAINT MONO (-2625 3050);
DISPLAY INVISIBLE (-2625 3050);
FORCEPROP 2 LAST CDS_LIB mstr_standard
J 0
(-2600 3000);
PAINT ORANGE (-2600 3000);
DISPLAY INVISIBLE (-2600 3000);
FORCEPROP 1 LAST PATH I34
J 2
(-2598 3000);
DISPLAY 0.872340 (-2598 3000);
PAINT GREEN (-2598 3000);
DISPLAY INVISIBLE (-2598 3000);
FORCEPROP 1 LAST BODY_TYPE PLUMBING
J 2
(-2600 2950);
DISPLAY 0.872340 (-2600 2950);
PAINT GREEN (-2600 2950);
DISPLAY INVISIBLE (-2600 2950);
FORCEPROP 1 LAST HDL_TAP TRUE
J 2
(-2925 2875);
DISPLAY 0.872340 (-2925 2875);
PAINT GREEN (-2925 2875);
DISPLAY INVISIBLE (-2925 2875);
FORCEADD TAP..6
R 2
(-2600 2900);
FORCEPROP 3 LASTPIN (-2650 2900) SIG_NAME DMI_CPU0_PCH_RX_DN<1>
J 0
(-2640 2910);
DISPLAY 0.659574 (-2640 2910);
PAINT MONO (-2640 2910);
DISPLAY INVISIBLE (-2640 2910);
FORCEPROP 1 LASTPIN (-2650 2900) BN 1
J 2
(-2598 2908);
DISPLAY 0.617021 (-2598 2908);
PAINT VIOLET (-2598 2908);
FORCEPROP 2 LAST BOM_COST SB
J 0
(-2625 2950);
DISPLAY 0.744681 (-2625 2950);
PAINT MONO (-2625 2950);
DISPLAY INVISIBLE (-2625 2950);
FORCEPROP 2 LAST CDS_LIB mstr_standard
J 0
(-2600 2900);
PAINT ORANGE (-2600 2900);
DISPLAY INVISIBLE (-2600 2900);
FORCEPROP 1 LAST PATH I35
J 2
(-2598 2900);
DISPLAY 0.872340 (-2598 2900);
PAINT GREEN (-2598 2900);
DISPLAY INVISIBLE (-2598 2900);
FORCEPROP 1 LAST BODY_TYPE PLUMBING
J 2
(-2600 2850);
DISPLAY 0.872340 (-2600 2850);
PAINT GREEN (-2600 2850);
DISPLAY INVISIBLE (-2600 2850);
FORCEPROP 1 LAST HDL_TAP TRUE
J 2
(-2925 2775);
DISPLAY 0.872340 (-2925 2775);
PAINT GREEN (-2925 2775);
DISPLAY INVISIBLE (-2925 2775);
FORCEADD TAP..6
R 2
(-2600 2800);
FORCEPROP 3 LASTPIN (-2650 2800) SIG_NAME DMI_CPU0_PCH_RX_DN<0>
J 0
(-2640 2810);
DISPLAY 0.659574 (-2640 2810);
PAINT MONO (-2640 2810);
DISPLAY INVISIBLE (-2640 2810);
FORCEPROP 1 LASTPIN (-2650 2800) BN 0
J 2
(-2598 2808);
DISPLAY 0.617021 (-2598 2808);
PAINT VIOLET (-2598 2808);
FORCEPROP 2 LAST CDS_LIB mstr_standard
J 0
(-2600 2800);
PAINT ORANGE (-2600 2800);
DISPLAY INVISIBLE (-2600 2800);
FORCEPROP 2 LAST BOM_COST SB
J 0
(-2625 2850);
DISPLAY 0.744681 (-2625 2850);
PAINT MONO (-2625 2850);
DISPLAY INVISIBLE (-2625 2850);
FORCEPROP 1 LAST PATH I36
J 2
(-2598 2800);
DISPLAY 0.872340 (-2598 2800);
PAINT GREEN (-2598 2800);
DISPLAY INVISIBLE (-2598 2800);
FORCEPROP 1 LAST BODY_TYPE PLUMBING
J 2
(-2600 2750);
DISPLAY 0.872340 (-2600 2750);
PAINT GREEN (-2600 2750);
DISPLAY INVISIBLE (-2600 2750);
FORCEPROP 1 LAST HDL_TAP TRUE
J 2
(-2925 2675);
DISPLAY 0.872340 (-2925 2675);
PAINT GREEN (-2925 2675);
DISPLAY INVISIBLE (-2925 2675);
FORCEADD OFFPAGE..2
(-1700 3350);
FORCEPROP 2 LAST $XR0 129 
J 0
(-1511 3350);
DISPLAY 0.638298 (-1511 3350);
PAINT MONO (-1511 3350);
FORCEPROP 2 LAST BOM_COST SB
J 0
(-1950 3400);
DISPLAY 0.744681 (-1950 3400);
PAINT MONO (-1950 3400);
DISPLAY INVISIBLE (-1950 3400);
FORCEPROP 2 LAST CDS_LIB mstr_standard
J 0
(-1700 3350);
PAINT ORANGE (-1700 3350);
DISPLAY INVISIBLE (-1700 3350);
FORCEPROP 2 LAST PATH I38
J 0
(-1525 3425);
DISPLAY 1.021277 (-1525 3425);
PAINT ORANGE (-1525 3425);
DISPLAY INVISIBLE (-1525 3425);
FORCEPROP 1 LAST OFFPAGE TRUE
J 0
(-1375 3225);
DISPLAY 0.872340 (-1375 3225);
PAINT GREEN (-1375 3225);
DISPLAY INVISIBLE (-1375 3225);
FORCEPROP 1 LAST COMMENT_BODY TRUE
J 0
(-1745 3255);
DISPLAY 0.872340 (-1745 3255);
PAINT PEACH (-1745 3255);
DISPLAY INVISIBLE (-1745 3255);
FORCEADD OFFPAGE..2
(-1700 3250);
FORCEPROP 2 LAST $XR0 129 
J 0
(-1511 3250);
DISPLAY 0.638298 (-1511 3250);
PAINT MONO (-1511 3250);
FORCEPROP 2 LAST BOM_COST SB
J 0
(-1950 3300);
DISPLAY 0.744681 (-1950 3300);
PAINT MONO (-1950 3300);
DISPLAY INVISIBLE (-1950 3300);
FORCEPROP 2 LAST CDS_LIB mstr_standard
J 0
(-1700 3250);
PAINT ORANGE (-1700 3250);
DISPLAY INVISIBLE (-1700 3250);
FORCEPROP 2 LAST PATH I39
J 0
(-1525 3325);
DISPLAY 1.021277 (-1525 3325);
PAINT ORANGE (-1525 3325);
DISPLAY INVISIBLE (-1525 3325);
FORCEPROP 1 LAST OFFPAGE TRUE
J 0
(-1375 3125);
DISPLAY 0.872340 (-1375 3125);
PAINT GREEN (-1375 3125);
DISPLAY INVISIBLE (-1375 3125);
FORCEPROP 1 LAST COMMENT_BODY TRUE
J 0
(-1745 3155);
DISPLAY 0.872340 (-1745 3155);
PAINT PEACH (-1745 3155);
DISPLAY INVISIBLE (-1745 3155);
FORCEADD OFFPAGE..1
(-6975 1100);
FORCEPROP 2 LAST $XR0 107 
J 0
(-7227 1100);
DISPLAY 0.638298 (-7227 1100);
PAINT MONO (-7227 1100);
FORCEPROP 2 LAST CDS_LIB mstr_standard
J 0
(-6975 1100);
PAINT ORANGE (-6975 1100);
DISPLAY INVISIBLE (-6975 1100);
FORCEPROP 2 LAST PATH I40
J 0
(-7175 1150);
DISPLAY 1.021277 (-7175 1150);
PAINT ORANGE (-7175 1150);
DISPLAY INVISIBLE (-7175 1150);
FORCEPROP 1 LAST OFFPAGE TRUE
J 0
(-6650 975);
DISPLAY 1.170213 (-6650 975);
PAINT GREEN (-6650 975);
DISPLAY INVISIBLE (-6650 975);
FORCEPROP 1 LAST COMMENT_BODY TRUE
J 0
(-6850 1000);
DISPLAY 1.170213 (-6850 1000);
PAINT PEACH (-6850 1000);
DISPLAY INVISIBLE (-6850 1000);
FORCEADD OFFPAGE..1
(-6975 1025);
FORCEPROP 2 LAST $XR0 107 
J 0
(-7227 1025);
DISPLAY 0.638298 (-7227 1025);
PAINT MONO (-7227 1025);
FORCEPROP 2 LAST CDS_LIB mstr_standard
J 0
(-6975 1025);
PAINT ORANGE (-6975 1025);
DISPLAY INVISIBLE (-6975 1025);
FORCEPROP 2 LAST PATH I41
J 0
(-7175 1075);
DISPLAY 1.021277 (-7175 1075);
PAINT ORANGE (-7175 1075);
DISPLAY INVISIBLE (-7175 1075);
FORCEPROP 1 LAST OFFPAGE TRUE
J 0
(-6650 900);
DISPLAY 1.170213 (-6650 900);
PAINT GREEN (-6650 900);
DISPLAY INVISIBLE (-6650 900);
FORCEPROP 1 LAST COMMENT_BODY TRUE
J 0
(-6850 925);
DISPLAY 1.170213 (-6850 925);
PAINT PEACH (-6850 925);
DISPLAY INVISIBLE (-6850 925);
FORCEADD TAP..6
(-5625 1150);
FORCEPROP 3 LASTPIN (-5575 1150) SIG_NAME P3E_CPU0_PE1_PCH_TXN<0>
J 0
(-5565 1160);
DISPLAY 0.659574 (-5565 1160);
PAINT MONO (-5565 1160);
DISPLAY INVISIBLE (-5565 1160);
FORCEPROP 1 LASTPIN (-5575 1150) BN 0
J 0
(-5627 1158);
DISPLAY 0.617021 (-5627 1158);
PAINT VIOLET (-5627 1158);
FORCEPROP 2 LAST CDS_LIB mstr_standard
J 0
(-5625 1150);
PAINT ORANGE (-5625 1150);
DISPLAY INVISIBLE (-5625 1150);
FORCEPROP 1 LAST PATH I42
J 0
(-5627 1150);
DISPLAY 0.872340 (-5627 1150);
PAINT GREEN (-5627 1150);
DISPLAY INVISIBLE (-5627 1150);
FORCEPROP 1 LAST BODY_TYPE PLUMBING
J 0
(-5625 1100);
DISPLAY 1.170213 (-5625 1100);
PAINT GREEN (-5625 1100);
DISPLAY INVISIBLE (-5625 1100);
FORCEPROP 1 LAST HDL_TAP TRUE
J 0
(-5300 1025);
DISPLAY 1.170213 (-5300 1025);
PAINT ORANGE (-5300 1025);
DISPLAY INVISIBLE (-5300 1025);
FORCEADD TAP..6
(-5625 1250);
FORCEPROP 3 LASTPIN (-5575 1250) SIG_NAME P3E_CPU0_PE1_PCH_TXN<1>
J 0
(-5565 1260);
DISPLAY 0.659574 (-5565 1260);
PAINT MONO (-5565 1260);
DISPLAY INVISIBLE (-5565 1260);
FORCEPROP 1 LASTPIN (-5575 1250) BN 1
J 0
(-5627 1258);
DISPLAY 0.617021 (-5627 1258);
PAINT VIOLET (-5627 1258);
FORCEPROP 2 LAST CDS_LIB mstr_standard
J 0
(-5625 1250);
PAINT ORANGE (-5625 1250);
DISPLAY INVISIBLE (-5625 1250);
FORCEPROP 1 LAST PATH I43
J 0
(-5627 1250);
DISPLAY 0.872340 (-5627 1250);
PAINT GREEN (-5627 1250);
DISPLAY INVISIBLE (-5627 1250);
FORCEPROP 1 LAST BODY_TYPE PLUMBING
J 0
(-5625 1200);
DISPLAY 1.170213 (-5625 1200);
PAINT GREEN (-5625 1200);
DISPLAY INVISIBLE (-5625 1200);
FORCEPROP 1 LAST HDL_TAP TRUE
J 0
(-5300 1125);
DISPLAY 1.170213 (-5300 1125);
PAINT ORANGE (-5300 1125);
DISPLAY INVISIBLE (-5300 1125);
FORCEADD TAP..6
(-5625 1450);
FORCEPROP 3 LASTPIN (-5575 1450) SIG_NAME P3E_CPU0_PE1_PCH_TXN<3>
J 0
(-5565 1460);
DISPLAY 0.659574 (-5565 1460);
PAINT MONO (-5565 1460);
DISPLAY INVISIBLE (-5565 1460);
FORCEPROP 1 LASTPIN (-5575 1450) BN 3
J 0
(-5627 1458);
DISPLAY 0.617021 (-5627 1458);
PAINT VIOLET (-5627 1458);
FORCEPROP 2 LAST CDS_LIB mstr_standard
J 0
(-5625 1450);
PAINT ORANGE (-5625 1450);
DISPLAY INVISIBLE (-5625 1450);
FORCEPROP 1 LAST PATH I44
J 0
(-5627 1450);
DISPLAY 0.872340 (-5627 1450);
PAINT GREEN (-5627 1450);
DISPLAY INVISIBLE (-5627 1450);
FORCEPROP 1 LAST BODY_TYPE PLUMBING
J 0
(-5625 1400);
DISPLAY 1.170213 (-5625 1400);
PAINT GREEN (-5625 1400);
DISPLAY INVISIBLE (-5625 1400);
FORCEPROP 1 LAST HDL_TAP TRUE
J 0
(-5300 1325);
DISPLAY 1.170213 (-5300 1325);
PAINT ORANGE (-5300 1325);
DISPLAY INVISIBLE (-5300 1325);
FORCEADD TAP..6
(-5625 1350);
FORCEPROP 3 LASTPIN (-5575 1350) SIG_NAME P3E_CPU0_PE1_PCH_TXN<2>
J 0
(-5565 1360);
DISPLAY 0.659574 (-5565 1360);
PAINT MONO (-5565 1360);
DISPLAY INVISIBLE (-5565 1360);
FORCEPROP 1 LASTPIN (-5575 1350) BN 2
J 0
(-5627 1358);
DISPLAY 0.617021 (-5627 1358);
PAINT VIOLET (-5627 1358);
FORCEPROP 2 LAST CDS_LIB mstr_standard
J 0
(-5625 1350);
PAINT ORANGE (-5625 1350);
DISPLAY INVISIBLE (-5625 1350);
FORCEPROP 1 LAST PATH I45
J 0
(-5627 1350);
DISPLAY 0.872340 (-5627 1350);
PAINT GREEN (-5627 1350);
DISPLAY INVISIBLE (-5627 1350);
FORCEPROP 1 LAST BODY_TYPE PLUMBING
J 0
(-5625 1300);
DISPLAY 1.170213 (-5625 1300);
PAINT GREEN (-5625 1300);
DISPLAY INVISIBLE (-5625 1300);
FORCEPROP 1 LAST HDL_TAP TRUE
J 0
(-5300 1225);
DISPLAY 1.170213 (-5300 1225);
PAINT ORANGE (-5300 1225);
DISPLAY INVISIBLE (-5300 1225);
FORCEADD TAP..6
(-5625 1550);
FORCEPROP 3 LASTPIN (-5575 1550) SIG_NAME P3E_CPU0_PE1_PCH_TXN<4>
J 0
(-5565 1560);
DISPLAY 0.659574 (-5565 1560);
PAINT MONO (-5565 1560);
DISPLAY INVISIBLE (-5565 1560);
FORCEPROP 1 LASTPIN (-5575 1550) BN 4
J 0
(-5627 1558);
DISPLAY 0.617021 (-5627 1558);
PAINT VIOLET (-5627 1558);
FORCEPROP 2 LAST CDS_LIB mstr_standard
J 0
(-5625 1550);
PAINT ORANGE (-5625 1550);
DISPLAY INVISIBLE (-5625 1550);
FORCEPROP 1 LAST PATH I46
J 0
(-5627 1550);
DISPLAY 0.872340 (-5627 1550);
PAINT GREEN (-5627 1550);
DISPLAY INVISIBLE (-5627 1550);
FORCEPROP 1 LAST BODY_TYPE PLUMBING
J 0
(-5625 1500);
DISPLAY 1.170213 (-5625 1500);
PAINT GREEN (-5625 1500);
DISPLAY INVISIBLE (-5625 1500);
FORCEPROP 1 LAST HDL_TAP TRUE
J 0
(-5300 1425);
DISPLAY 1.170213 (-5300 1425);
PAINT ORANGE (-5300 1425);
DISPLAY INVISIBLE (-5300 1425);
FORCEADD TAP..6
(-5625 1650);
FORCEPROP 3 LASTPIN (-5575 1650) SIG_NAME P3E_CPU0_PE1_PCH_TXN<5>
J 0
(-5565 1660);
DISPLAY 0.659574 (-5565 1660);
PAINT MONO (-5565 1660);
DISPLAY INVISIBLE (-5565 1660);
FORCEPROP 1 LASTPIN (-5575 1650) BN 5
J 0
(-5627 1658);
DISPLAY 0.617021 (-5627 1658);
PAINT VIOLET (-5627 1658);
FORCEPROP 2 LAST CDS_LIB mstr_standard
J 0
(-5625 1650);
PAINT ORANGE (-5625 1650);
DISPLAY INVISIBLE (-5625 1650);
FORCEPROP 1 LAST PATH I47
J 0
(-5627 1650);
DISPLAY 0.872340 (-5627 1650);
PAINT GREEN (-5627 1650);
DISPLAY INVISIBLE (-5627 1650);
FORCEPROP 1 LAST BODY_TYPE PLUMBING
J 0
(-5625 1600);
DISPLAY 1.170213 (-5625 1600);
PAINT GREEN (-5625 1600);
DISPLAY INVISIBLE (-5625 1600);
FORCEPROP 1 LAST HDL_TAP TRUE
J 0
(-5300 1525);
DISPLAY 1.170213 (-5300 1525);
PAINT ORANGE (-5300 1525);
DISPLAY INVISIBLE (-5300 1525);
FORCEADD TAP..6
(-5625 1750);
FORCEPROP 3 LASTPIN (-5575 1750) SIG_NAME P3E_CPU0_PE1_PCH_TXN<6>
J 0
(-5565 1760);
DISPLAY 0.659574 (-5565 1760);
PAINT MONO (-5565 1760);
DISPLAY INVISIBLE (-5565 1760);
FORCEPROP 1 LASTPIN (-5575 1750) BN 6
J 0
(-5627 1758);
DISPLAY 0.617021 (-5627 1758);
PAINT VIOLET (-5627 1758);
FORCEPROP 2 LAST CDS_LIB mstr_standard
J 0
(-5625 1750);
PAINT ORANGE (-5625 1750);
DISPLAY INVISIBLE (-5625 1750);
FORCEPROP 1 LAST PATH I48
J 0
(-5627 1750);
DISPLAY 0.872340 (-5627 1750);
PAINT GREEN (-5627 1750);
DISPLAY INVISIBLE (-5627 1750);
FORCEPROP 1 LAST BODY_TYPE PLUMBING
J 0
(-5625 1700);
DISPLAY 1.170213 (-5625 1700);
PAINT GREEN (-5625 1700);
DISPLAY INVISIBLE (-5625 1700);
FORCEPROP 1 LAST HDL_TAP TRUE
J 0
(-5300 1625);
DISPLAY 1.170213 (-5300 1625);
PAINT ORANGE (-5300 1625);
DISPLAY INVISIBLE (-5300 1625);
FORCEADD TAP..6
(-5625 1850);
FORCEPROP 3 LASTPIN (-5575 1850) SIG_NAME P3E_CPU0_PE1_PCH_TXN<7>
J 0
(-5565 1860);
DISPLAY 0.659574 (-5565 1860);
PAINT MONO (-5565 1860);
DISPLAY INVISIBLE (-5565 1860);
FORCEPROP 1 LASTPIN (-5575 1850) BN 7
J 0
(-5627 1858);
DISPLAY 0.617021 (-5627 1858);
PAINT VIOLET (-5627 1858);
FORCEPROP 2 LAST CDS_LIB mstr_standard
J 0
(-5625 1850);
PAINT ORANGE (-5625 1850);
DISPLAY INVISIBLE (-5625 1850);
FORCEPROP 1 LAST PATH I50
J 0
(-5627 1850);
DISPLAY 0.872340 (-5627 1850);
PAINT GREEN (-5627 1850);
DISPLAY INVISIBLE (-5627 1850);
FORCEPROP 1 LAST BODY_TYPE PLUMBING
J 0
(-5625 1800);
DISPLAY 1.170213 (-5625 1800);
PAINT GREEN (-5625 1800);
DISPLAY INVISIBLE (-5625 1800);
FORCEPROP 1 LAST HDL_TAP TRUE
J 0
(-5300 1725);
DISPLAY 1.170213 (-5300 1725);
PAINT ORANGE (-5300 1725);
DISPLAY INVISIBLE (-5300 1725);
FORCEADD TAP..6
(-5500 1200);
FORCEPROP 3 LASTPIN (-5450 1200) SIG_NAME P3E_CPU0_PE1_PCH_TXP<0>
J 0
(-5440 1210);
DISPLAY 0.659574 (-5440 1210);
PAINT MONO (-5440 1210);
DISPLAY INVISIBLE (-5440 1210);
FORCEPROP 1 LASTPIN (-5450 1200) BN 0
J 0
(-5502 1208);
DISPLAY 0.617021 (-5502 1208);
PAINT VIOLET (-5502 1208);
FORCEPROP 2 LAST CDS_LIB mstr_standard
J 0
(-5500 1200);
PAINT ORANGE (-5500 1200);
DISPLAY INVISIBLE (-5500 1200);
FORCEPROP 1 LAST PATH I58
J 0
(-5502 1200);
DISPLAY 0.872340 (-5502 1200);
PAINT GREEN (-5502 1200);
DISPLAY INVISIBLE (-5502 1200);
FORCEPROP 1 LAST BODY_TYPE PLUMBING
J 0
(-5500 1150);
DISPLAY 1.170213 (-5500 1150);
PAINT GREEN (-5500 1150);
DISPLAY INVISIBLE (-5500 1150);
FORCEPROP 1 LAST HDL_TAP TRUE
J 0
(-5175 1075);
DISPLAY 1.170213 (-5175 1075);
PAINT ORANGE (-5175 1075);
DISPLAY INVISIBLE (-5175 1075);
FORCEADD TAP..6
(-5500 1300);
FORCEPROP 3 LASTPIN (-5450 1300) SIG_NAME P3E_CPU0_PE1_PCH_TXP<1>
J 0
(-5440 1310);
DISPLAY 0.659574 (-5440 1310);
PAINT MONO (-5440 1310);
DISPLAY INVISIBLE (-5440 1310);
FORCEPROP 1 LASTPIN (-5450 1300) BN 1
J 0
(-5502 1308);
DISPLAY 0.617021 (-5502 1308);
PAINT VIOLET (-5502 1308);
FORCEPROP 2 LAST CDS_LIB mstr_standard
J 0
(-5500 1300);
PAINT ORANGE (-5500 1300);
DISPLAY INVISIBLE (-5500 1300);
FORCEPROP 1 LAST PATH I59
J 0
(-5502 1300);
DISPLAY 0.872340 (-5502 1300);
PAINT GREEN (-5502 1300);
DISPLAY INVISIBLE (-5502 1300);
FORCEPROP 1 LAST BODY_TYPE PLUMBING
J 0
(-5500 1250);
DISPLAY 1.170213 (-5500 1250);
PAINT GREEN (-5500 1250);
DISPLAY INVISIBLE (-5500 1250);
FORCEPROP 1 LAST HDL_TAP TRUE
J 0
(-5175 1175);
DISPLAY 1.170213 (-5175 1175);
PAINT ORANGE (-5175 1175);
DISPLAY INVISIBLE (-5175 1175);
FORCEADD TAP..6
(-5500 1400);
FORCEPROP 3 LASTPIN (-5450 1400) SIG_NAME P3E_CPU0_PE1_PCH_TXP<2>
J 0
(-5440 1410);
DISPLAY 0.659574 (-5440 1410);
PAINT MONO (-5440 1410);
DISPLAY INVISIBLE (-5440 1410);
FORCEPROP 1 LASTPIN (-5450 1400) BN 2
J 0
(-5502 1408);
DISPLAY 0.617021 (-5502 1408);
PAINT VIOLET (-5502 1408);
FORCEPROP 2 LAST CDS_LIB mstr_standard
J 0
(-5500 1400);
PAINT ORANGE (-5500 1400);
DISPLAY INVISIBLE (-5500 1400);
FORCEPROP 1 LAST PATH I60
J 0
(-5502 1400);
DISPLAY 0.872340 (-5502 1400);
PAINT GREEN (-5502 1400);
DISPLAY INVISIBLE (-5502 1400);
FORCEPROP 1 LAST BODY_TYPE PLUMBING
J 0
(-5500 1350);
DISPLAY 1.170213 (-5500 1350);
PAINT GREEN (-5500 1350);
DISPLAY INVISIBLE (-5500 1350);
FORCEPROP 1 LAST HDL_TAP TRUE
J 0
(-5175 1275);
DISPLAY 1.170213 (-5175 1275);
PAINT ORANGE (-5175 1275);
DISPLAY INVISIBLE (-5175 1275);
FORCEADD TAP..6
(-5500 1500);
FORCEPROP 3 LASTPIN (-5450 1500) SIG_NAME P3E_CPU0_PE1_PCH_TXP<3>
J 0
(-5440 1510);
DISPLAY 0.659574 (-5440 1510);
PAINT MONO (-5440 1510);
DISPLAY INVISIBLE (-5440 1510);
FORCEPROP 1 LASTPIN (-5450 1500) BN 3
J 0
(-5502 1508);
DISPLAY 0.617021 (-5502 1508);
PAINT VIOLET (-5502 1508);
FORCEPROP 2 LAST CDS_LIB mstr_standard
J 0
(-5500 1500);
PAINT ORANGE (-5500 1500);
DISPLAY INVISIBLE (-5500 1500);
FORCEPROP 1 LAST PATH I61
J 0
(-5502 1500);
DISPLAY 0.872340 (-5502 1500);
PAINT GREEN (-5502 1500);
DISPLAY INVISIBLE (-5502 1500);
FORCEPROP 1 LAST BODY_TYPE PLUMBING
J 0
(-5500 1450);
DISPLAY 1.170213 (-5500 1450);
PAINT GREEN (-5500 1450);
DISPLAY INVISIBLE (-5500 1450);
FORCEPROP 1 LAST HDL_TAP TRUE
J 0
(-5175 1375);
DISPLAY 1.170213 (-5175 1375);
PAINT ORANGE (-5175 1375);
DISPLAY INVISIBLE (-5175 1375);
FORCEADD TAP..6
(-5500 1700);
FORCEPROP 3 LASTPIN (-5450 1700) SIG_NAME P3E_CPU0_PE1_PCH_TXP<5>
J 0
(-5440 1710);
DISPLAY 0.659574 (-5440 1710);
PAINT MONO (-5440 1710);
DISPLAY INVISIBLE (-5440 1710);
FORCEPROP 1 LASTPIN (-5450 1700) BN 5
J 0
(-5502 1708);
DISPLAY 0.617021 (-5502 1708);
PAINT VIOLET (-5502 1708);
FORCEPROP 2 LAST CDS_LIB mstr_standard
J 0
(-5500 1700);
PAINT ORANGE (-5500 1700);
DISPLAY INVISIBLE (-5500 1700);
FORCEPROP 1 LAST PATH I62
J 0
(-5502 1700);
DISPLAY 0.872340 (-5502 1700);
PAINT GREEN (-5502 1700);
DISPLAY INVISIBLE (-5502 1700);
FORCEPROP 1 LAST BODY_TYPE PLUMBING
J 0
(-5500 1650);
DISPLAY 1.170213 (-5500 1650);
PAINT GREEN (-5500 1650);
DISPLAY INVISIBLE (-5500 1650);
FORCEPROP 1 LAST HDL_TAP TRUE
J 0
(-5175 1575);
DISPLAY 1.170213 (-5175 1575);
PAINT ORANGE (-5175 1575);
DISPLAY INVISIBLE (-5175 1575);
FORCEADD TAP..6
(-5500 1600);
FORCEPROP 3 LASTPIN (-5450 1600) SIG_NAME P3E_CPU0_PE1_PCH_TXP<4>
J 0
(-5440 1610);
DISPLAY 0.659574 (-5440 1610);
PAINT MONO (-5440 1610);
DISPLAY INVISIBLE (-5440 1610);
FORCEPROP 1 LASTPIN (-5450 1600) BN 4
J 0
(-5502 1608);
DISPLAY 0.617021 (-5502 1608);
PAINT VIOLET (-5502 1608);
FORCEPROP 2 LAST CDS_LIB mstr_standard
J 0
(-5500 1600);
PAINT ORANGE (-5500 1600);
DISPLAY INVISIBLE (-5500 1600);
FORCEPROP 1 LAST PATH I63
J 0
(-5502 1600);
DISPLAY 0.872340 (-5502 1600);
PAINT GREEN (-5502 1600);
DISPLAY INVISIBLE (-5502 1600);
FORCEPROP 1 LAST BODY_TYPE PLUMBING
J 0
(-5500 1550);
DISPLAY 1.170213 (-5500 1550);
PAINT GREEN (-5500 1550);
DISPLAY INVISIBLE (-5500 1550);
FORCEPROP 1 LAST HDL_TAP TRUE
J 0
(-5175 1475);
DISPLAY 1.170213 (-5175 1475);
PAINT ORANGE (-5175 1475);
DISPLAY INVISIBLE (-5175 1475);
FORCEADD TAP..6
(-5500 1800);
FORCEPROP 3 LASTPIN (-5450 1800) SIG_NAME P3E_CPU0_PE1_PCH_TXP<6>
J 0
(-5440 1810);
DISPLAY 0.659574 (-5440 1810);
PAINT MONO (-5440 1810);
DISPLAY INVISIBLE (-5440 1810);
FORCEPROP 1 LASTPIN (-5450 1800) BN 6
J 0
(-5502 1808);
DISPLAY 0.617021 (-5502 1808);
PAINT VIOLET (-5502 1808);
FORCEPROP 2 LAST CDS_LIB mstr_standard
J 0
(-5500 1800);
PAINT ORANGE (-5500 1800);
DISPLAY INVISIBLE (-5500 1800);
FORCEPROP 1 LAST PATH I64
J 0
(-5502 1800);
DISPLAY 0.872340 (-5502 1800);
PAINT GREEN (-5502 1800);
DISPLAY INVISIBLE (-5502 1800);
FORCEPROP 1 LAST BODY_TYPE PLUMBING
J 0
(-5500 1750);
DISPLAY 1.170213 (-5500 1750);
PAINT GREEN (-5500 1750);
DISPLAY INVISIBLE (-5500 1750);
FORCEPROP 1 LAST HDL_TAP TRUE
J 0
(-5175 1675);
DISPLAY 1.170213 (-5175 1675);
PAINT ORANGE (-5175 1675);
DISPLAY INVISIBLE (-5175 1675);
FORCEADD TAP..6
(-5500 1900);
FORCEPROP 3 LASTPIN (-5450 1900) SIG_NAME P3E_CPU0_PE1_PCH_TXP<7>
J 0
(-5440 1910);
DISPLAY 0.659574 (-5440 1910);
PAINT MONO (-5440 1910);
DISPLAY INVISIBLE (-5440 1910);
FORCEPROP 1 LASTPIN (-5450 1900) BN 7
J 0
(-5502 1908);
DISPLAY 0.617021 (-5502 1908);
PAINT VIOLET (-5502 1908);
FORCEPROP 2 LAST CDS_LIB mstr_standard
J 0
(-5500 1900);
PAINT ORANGE (-5500 1900);
DISPLAY INVISIBLE (-5500 1900);
FORCEPROP 1 LAST PATH I65
J 0
(-5502 1900);
DISPLAY 0.872340 (-5502 1900);
PAINT GREEN (-5502 1900);
DISPLAY INVISIBLE (-5502 1900);
FORCEPROP 1 LAST BODY_TYPE PLUMBING
J 0
(-5500 1850);
DISPLAY 1.170213 (-5500 1850);
PAINT GREEN (-5500 1850);
DISPLAY INVISIBLE (-5500 1850);
FORCEPROP 1 LAST HDL_TAP TRUE
J 0
(-5175 1775);
DISPLAY 1.170213 (-5175 1775);
PAINT ORANGE (-5175 1775);
DISPLAY INVISIBLE (-5175 1775);
FORCEADD TAP..1
(-2725 1200);
FORCEPROP 3 LASTPIN (-2775 1200) SIG_NAME P3E_CPU0_PE1_PCH_RXP<0>
J 0
(-2765 1210);
DISPLAY 0.659574 (-2765 1210);
PAINT MONO (-2765 1210);
DISPLAY INVISIBLE (-2765 1210);
FORCEPROP 1 LASTPIN (-2775 1200) BN 0
J 0
(-2787 1208);
DISPLAY 0.617021 (-2787 1208);
PAINT VIOLET (-2787 1208);
FORCEPROP 2 LAST CDS_LIB mstr_standard
J 0
(-2725 1200);
PAINT ORANGE (-2725 1200);
DISPLAY INVISIBLE (-2725 1200);
FORCEPROP 1 LAST PATH I74
J 0
(-2727 1200);
DISPLAY 0.872340 (-2727 1200);
PAINT GREEN (-2727 1200);
DISPLAY INVISIBLE (-2727 1200);
FORCEPROP 1 LAST BODY_TYPE PLUMBING
J 0
(-2725 1250);
DISPLAY 1.170213 (-2725 1250);
PAINT GREEN (-2725 1250);
DISPLAY INVISIBLE (-2725 1250);
FORCEPROP 1 LAST HDL_TAP TRUE
J 0
(-2400 1075);
DISPLAY 1.170213 (-2400 1075);
PAINT ORANGE (-2400 1075);
DISPLAY INVISIBLE (-2400 1075);
FORCEADD TAP..1
(-2725 1300);
FORCEPROP 3 LASTPIN (-2775 1300) SIG_NAME P3E_CPU0_PE1_PCH_RXP<1>
J 0
(-2765 1310);
DISPLAY 0.659574 (-2765 1310);
PAINT MONO (-2765 1310);
DISPLAY INVISIBLE (-2765 1310);
FORCEPROP 1 LASTPIN (-2775 1300) BN 1
J 0
(-2787 1308);
DISPLAY 0.617021 (-2787 1308);
PAINT VIOLET (-2787 1308);
FORCEPROP 2 LAST CDS_LIB mstr_standard
J 0
(-2725 1300);
PAINT ORANGE (-2725 1300);
DISPLAY INVISIBLE (-2725 1300);
FORCEPROP 1 LAST PATH I75
J 0
(-2727 1300);
DISPLAY 0.872340 (-2727 1300);
PAINT GREEN (-2727 1300);
DISPLAY INVISIBLE (-2727 1300);
FORCEPROP 1 LAST BODY_TYPE PLUMBING
J 0
(-2725 1350);
DISPLAY 1.170213 (-2725 1350);
PAINT GREEN (-2725 1350);
DISPLAY INVISIBLE (-2725 1350);
FORCEPROP 1 LAST HDL_TAP TRUE
J 0
(-2400 1175);
DISPLAY 1.170213 (-2400 1175);
PAINT ORANGE (-2400 1175);
DISPLAY INVISIBLE (-2400 1175);
FORCEADD TAP..1
(-2725 1400);
FORCEPROP 3 LASTPIN (-2775 1400) SIG_NAME P3E_CPU0_PE1_PCH_RXP<2>
J 0
(-2765 1410);
DISPLAY 0.659574 (-2765 1410);
PAINT MONO (-2765 1410);
DISPLAY INVISIBLE (-2765 1410);
FORCEPROP 1 LASTPIN (-2775 1400) BN 2
J 0
(-2787 1408);
DISPLAY 0.617021 (-2787 1408);
PAINT VIOLET (-2787 1408);
FORCEPROP 2 LAST CDS_LIB mstr_standard
J 0
(-2725 1400);
PAINT ORANGE (-2725 1400);
DISPLAY INVISIBLE (-2725 1400);
FORCEPROP 1 LAST PATH I76
J 0
(-2727 1400);
DISPLAY 0.872340 (-2727 1400);
PAINT GREEN (-2727 1400);
DISPLAY INVISIBLE (-2727 1400);
FORCEPROP 1 LAST BODY_TYPE PLUMBING
J 0
(-2725 1450);
DISPLAY 1.170213 (-2725 1450);
PAINT GREEN (-2725 1450);
DISPLAY INVISIBLE (-2725 1450);
FORCEPROP 1 LAST HDL_TAP TRUE
J 0
(-2400 1275);
DISPLAY 1.170213 (-2400 1275);
PAINT ORANGE (-2400 1275);
DISPLAY INVISIBLE (-2400 1275);
FORCEADD TAP..1
(-2725 1500);
FORCEPROP 3 LASTPIN (-2775 1500) SIG_NAME P3E_CPU0_PE1_PCH_RXP<3>
J 0
(-2765 1510);
DISPLAY 0.659574 (-2765 1510);
PAINT MONO (-2765 1510);
DISPLAY INVISIBLE (-2765 1510);
FORCEPROP 1 LASTPIN (-2775 1500) BN 3
J 0
(-2787 1508);
DISPLAY 0.617021 (-2787 1508);
PAINT VIOLET (-2787 1508);
FORCEPROP 2 LAST CDS_LIB mstr_standard
J 0
(-2725 1500);
PAINT ORANGE (-2725 1500);
DISPLAY INVISIBLE (-2725 1500);
FORCEPROP 1 LAST PATH I77
J 0
(-2727 1500);
DISPLAY 0.872340 (-2727 1500);
PAINT GREEN (-2727 1500);
DISPLAY INVISIBLE (-2727 1500);
FORCEPROP 1 LAST BODY_TYPE PLUMBING
J 0
(-2725 1550);
DISPLAY 1.170213 (-2725 1550);
PAINT GREEN (-2725 1550);
DISPLAY INVISIBLE (-2725 1550);
FORCEPROP 1 LAST HDL_TAP TRUE
J 0
(-2400 1375);
DISPLAY 1.170213 (-2400 1375);
PAINT ORANGE (-2400 1375);
DISPLAY INVISIBLE (-2400 1375);
FORCEADD TAP..1
(-2725 1600);
FORCEPROP 3 LASTPIN (-2775 1600) SIG_NAME P3E_CPU0_PE1_PCH_RXP<4>
J 0
(-2765 1610);
DISPLAY 0.659574 (-2765 1610);
PAINT MONO (-2765 1610);
DISPLAY INVISIBLE (-2765 1610);
FORCEPROP 1 LASTPIN (-2775 1600) BN 4
J 0
(-2787 1608);
DISPLAY 0.617021 (-2787 1608);
PAINT VIOLET (-2787 1608);
FORCEPROP 2 LAST CDS_LIB mstr_standard
J 0
(-2725 1600);
PAINT ORANGE (-2725 1600);
DISPLAY INVISIBLE (-2725 1600);
FORCEPROP 1 LAST PATH I78
J 0
(-2727 1600);
DISPLAY 0.872340 (-2727 1600);
PAINT GREEN (-2727 1600);
DISPLAY INVISIBLE (-2727 1600);
FORCEPROP 1 LAST BODY_TYPE PLUMBING
J 0
(-2725 1650);
DISPLAY 1.170213 (-2725 1650);
PAINT GREEN (-2725 1650);
DISPLAY INVISIBLE (-2725 1650);
FORCEPROP 1 LAST HDL_TAP TRUE
J 0
(-2400 1475);
DISPLAY 1.170213 (-2400 1475);
PAINT ORANGE (-2400 1475);
DISPLAY INVISIBLE (-2400 1475);
FORCEADD TAP..1
(-2600 1250);
FORCEPROP 3 LASTPIN (-2650 1250) SIG_NAME P3E_CPU0_PE1_PCH_RXN<1>
J 0
(-2640 1260);
DISPLAY 0.659574 (-2640 1260);
PAINT MONO (-2640 1260);
DISPLAY INVISIBLE (-2640 1260);
FORCEPROP 1 LASTPIN (-2650 1250) BN 1
J 0
(-2662 1258);
DISPLAY 0.617021 (-2662 1258);
PAINT VIOLET (-2662 1258);
FORCEPROP 2 LAST CDS_LIB mstr_standard
J 0
(-2600 1250);
PAINT ORANGE (-2600 1250);
DISPLAY INVISIBLE (-2600 1250);
FORCEPROP 1 LAST PATH I79
J 0
(-2602 1250);
DISPLAY 0.872340 (-2602 1250);
PAINT GREEN (-2602 1250);
DISPLAY INVISIBLE (-2602 1250);
FORCEPROP 1 LAST BODY_TYPE PLUMBING
J 0
(-2600 1300);
DISPLAY 1.170213 (-2600 1300);
PAINT GREEN (-2600 1300);
DISPLAY INVISIBLE (-2600 1300);
FORCEPROP 1 LAST HDL_TAP TRUE
J 0
(-2275 1125);
DISPLAY 1.170213 (-2275 1125);
PAINT ORANGE (-2275 1125);
DISPLAY INVISIBLE (-2275 1125);
FORCEADD TAP..1
(-2600 1150);
FORCEPROP 3 LASTPIN (-2650 1150) SIG_NAME P3E_CPU0_PE1_PCH_RXN<0>
J 0
(-2640 1160);
DISPLAY 0.659574 (-2640 1160);
PAINT MONO (-2640 1160);
DISPLAY INVISIBLE (-2640 1160);
FORCEPROP 1 LASTPIN (-2650 1150) BN 0
J 0
(-2662 1158);
DISPLAY 0.617021 (-2662 1158);
PAINT VIOLET (-2662 1158);
FORCEPROP 2 LAST CDS_LIB mstr_standard
J 0
(-2600 1150);
PAINT ORANGE (-2600 1150);
DISPLAY INVISIBLE (-2600 1150);
FORCEPROP 1 LAST PATH I80
J 0
(-2602 1150);
DISPLAY 0.872340 (-2602 1150);
PAINT GREEN (-2602 1150);
DISPLAY INVISIBLE (-2602 1150);
FORCEPROP 1 LAST BODY_TYPE PLUMBING
J 0
(-2600 1200);
DISPLAY 1.170213 (-2600 1200);
PAINT GREEN (-2600 1200);
DISPLAY INVISIBLE (-2600 1200);
FORCEPROP 1 LAST HDL_TAP TRUE
J 0
(-2275 1025);
DISPLAY 1.170213 (-2275 1025);
PAINT ORANGE (-2275 1025);
DISPLAY INVISIBLE (-2275 1025);
FORCEADD TAP..1
(-2600 1350);
FORCEPROP 3 LASTPIN (-2650 1350) SIG_NAME P3E_CPU0_PE1_PCH_RXN<2>
J 0
(-2640 1360);
DISPLAY 0.659574 (-2640 1360);
PAINT MONO (-2640 1360);
DISPLAY INVISIBLE (-2640 1360);
FORCEPROP 1 LASTPIN (-2650 1350) BN 2
J 0
(-2662 1358);
DISPLAY 0.617021 (-2662 1358);
PAINT VIOLET (-2662 1358);
FORCEPROP 2 LAST CDS_LIB mstr_standard
J 0
(-2600 1350);
PAINT ORANGE (-2600 1350);
DISPLAY INVISIBLE (-2600 1350);
FORCEPROP 1 LAST PATH I81
J 0
(-2602 1350);
DISPLAY 0.872340 (-2602 1350);
PAINT GREEN (-2602 1350);
DISPLAY INVISIBLE (-2602 1350);
FORCEPROP 1 LAST BODY_TYPE PLUMBING
J 0
(-2600 1400);
DISPLAY 1.170213 (-2600 1400);
PAINT GREEN (-2600 1400);
DISPLAY INVISIBLE (-2600 1400);
FORCEPROP 1 LAST HDL_TAP TRUE
J 0
(-2275 1225);
DISPLAY 1.170213 (-2275 1225);
PAINT ORANGE (-2275 1225);
DISPLAY INVISIBLE (-2275 1225);
FORCEADD TAP..1
(-2600 1450);
FORCEPROP 3 LASTPIN (-2650 1450) SIG_NAME P3E_CPU0_PE1_PCH_RXN<3>
J 0
(-2640 1460);
DISPLAY 0.659574 (-2640 1460);
PAINT MONO (-2640 1460);
DISPLAY INVISIBLE (-2640 1460);
FORCEPROP 1 LASTPIN (-2650 1450) BN 3
J 0
(-2662 1458);
DISPLAY 0.617021 (-2662 1458);
PAINT VIOLET (-2662 1458);
FORCEPROP 2 LAST CDS_LIB mstr_standard
J 0
(-2600 1450);
PAINT ORANGE (-2600 1450);
DISPLAY INVISIBLE (-2600 1450);
FORCEPROP 1 LAST PATH I82
J 0
(-2602 1450);
DISPLAY 0.872340 (-2602 1450);
PAINT GREEN (-2602 1450);
DISPLAY INVISIBLE (-2602 1450);
FORCEPROP 1 LAST BODY_TYPE PLUMBING
J 0
(-2600 1500);
DISPLAY 1.170213 (-2600 1500);
PAINT GREEN (-2600 1500);
DISPLAY INVISIBLE (-2600 1500);
FORCEPROP 1 LAST HDL_TAP TRUE
J 0
(-2275 1325);
DISPLAY 1.170213 (-2275 1325);
PAINT ORANGE (-2275 1325);
DISPLAY INVISIBLE (-2275 1325);
FORCEADD TAP..1
(-2600 1650);
FORCEPROP 3 LASTPIN (-2650 1650) SIG_NAME P3E_CPU0_PE1_PCH_RXN<5>
J 0
(-2640 1660);
DISPLAY 0.659574 (-2640 1660);
PAINT MONO (-2640 1660);
DISPLAY INVISIBLE (-2640 1660);
FORCEPROP 1 LASTPIN (-2650 1650) BN 5
J 0
(-2662 1658);
DISPLAY 0.617021 (-2662 1658);
PAINT VIOLET (-2662 1658);
FORCEPROP 2 LAST CDS_LIB mstr_standard
J 0
(-2600 1650);
PAINT ORANGE (-2600 1650);
DISPLAY INVISIBLE (-2600 1650);
FORCEPROP 1 LAST PATH I83
J 0
(-2602 1650);
DISPLAY 0.872340 (-2602 1650);
PAINT GREEN (-2602 1650);
DISPLAY INVISIBLE (-2602 1650);
FORCEPROP 1 LAST BODY_TYPE PLUMBING
J 0
(-2600 1700);
DISPLAY 1.170213 (-2600 1700);
PAINT GREEN (-2600 1700);
DISPLAY INVISIBLE (-2600 1700);
FORCEPROP 1 LAST HDL_TAP TRUE
J 0
(-2275 1525);
DISPLAY 1.170213 (-2275 1525);
PAINT ORANGE (-2275 1525);
DISPLAY INVISIBLE (-2275 1525);
FORCEADD TAP..1
(-2600 1550);
FORCEPROP 3 LASTPIN (-2650 1550) SIG_NAME P3E_CPU0_PE1_PCH_RXN<4>
J 0
(-2640 1560);
DISPLAY 0.659574 (-2640 1560);
PAINT MONO (-2640 1560);
DISPLAY INVISIBLE (-2640 1560);
FORCEPROP 1 LASTPIN (-2650 1550) BN 4
J 0
(-2662 1558);
DISPLAY 0.617021 (-2662 1558);
PAINT VIOLET (-2662 1558);
FORCEPROP 2 LAST CDS_LIB mstr_standard
J 0
(-2600 1550);
PAINT ORANGE (-2600 1550);
DISPLAY INVISIBLE (-2600 1550);
FORCEPROP 1 LAST PATH I84
J 0
(-2602 1550);
DISPLAY 0.872340 (-2602 1550);
PAINT GREEN (-2602 1550);
DISPLAY INVISIBLE (-2602 1550);
FORCEPROP 1 LAST BODY_TYPE PLUMBING
J 0
(-2600 1600);
DISPLAY 1.170213 (-2600 1600);
PAINT GREEN (-2600 1600);
DISPLAY INVISIBLE (-2600 1600);
FORCEPROP 1 LAST HDL_TAP TRUE
J 0
(-2275 1425);
DISPLAY 1.170213 (-2275 1425);
PAINT ORANGE (-2275 1425);
DISPLAY INVISIBLE (-2275 1425);
FORCEADD TAP..1
(-2725 1700);
FORCEPROP 3 LASTPIN (-2775 1700) SIG_NAME P3E_CPU0_PE1_PCH_RXP<5>
J 0
(-2765 1710);
DISPLAY 0.659574 (-2765 1710);
PAINT MONO (-2765 1710);
DISPLAY INVISIBLE (-2765 1710);
FORCEPROP 1 LASTPIN (-2775 1700) BN 5
J 0
(-2787 1708);
DISPLAY 0.617021 (-2787 1708);
PAINT VIOLET (-2787 1708);
FORCEPROP 2 LAST CDS_LIB mstr_standard
J 0
(-2725 1700);
PAINT ORANGE (-2725 1700);
DISPLAY INVISIBLE (-2725 1700);
FORCEPROP 1 LAST PATH I85
J 0
(-2727 1700);
DISPLAY 0.872340 (-2727 1700);
PAINT GREEN (-2727 1700);
DISPLAY INVISIBLE (-2727 1700);
FORCEPROP 1 LAST BODY_TYPE PLUMBING
J 0
(-2725 1750);
DISPLAY 1.170213 (-2725 1750);
PAINT GREEN (-2725 1750);
DISPLAY INVISIBLE (-2725 1750);
FORCEPROP 1 LAST HDL_TAP TRUE
J 0
(-2400 1575);
DISPLAY 1.170213 (-2400 1575);
PAINT ORANGE (-2400 1575);
DISPLAY INVISIBLE (-2400 1575);
FORCEADD TAP..1
(-2725 1800);
FORCEPROP 3 LASTPIN (-2775 1800) SIG_NAME P3E_CPU0_PE1_PCH_RXP<6>
J 0
(-2765 1810);
DISPLAY 0.659574 (-2765 1810);
PAINT MONO (-2765 1810);
DISPLAY INVISIBLE (-2765 1810);
FORCEPROP 1 LASTPIN (-2775 1800) BN 6
J 0
(-2787 1808);
DISPLAY 0.617021 (-2787 1808);
PAINT VIOLET (-2787 1808);
FORCEPROP 2 LAST CDS_LIB mstr_standard
J 0
(-2725 1800);
PAINT ORANGE (-2725 1800);
DISPLAY INVISIBLE (-2725 1800);
FORCEPROP 1 LAST PATH I86
J 0
(-2727 1800);
DISPLAY 0.872340 (-2727 1800);
PAINT GREEN (-2727 1800);
DISPLAY INVISIBLE (-2727 1800);
FORCEPROP 1 LAST BODY_TYPE PLUMBING
J 0
(-2725 1850);
DISPLAY 1.170213 (-2725 1850);
PAINT GREEN (-2725 1850);
DISPLAY INVISIBLE (-2725 1850);
FORCEPROP 1 LAST HDL_TAP TRUE
J 0
(-2400 1675);
DISPLAY 1.170213 (-2400 1675);
PAINT ORANGE (-2400 1675);
DISPLAY INVISIBLE (-2400 1675);
FORCEADD TAP..1
(-2725 1900);
FORCEPROP 3 LASTPIN (-2775 1900) SIG_NAME P3E_CPU0_PE1_PCH_RXP<7>
J 0
(-2765 1910);
DISPLAY 0.659574 (-2765 1910);
PAINT MONO (-2765 1910);
DISPLAY INVISIBLE (-2765 1910);
FORCEPROP 1 LASTPIN (-2775 1900) BN 7
J 0
(-2787 1908);
DISPLAY 0.617021 (-2787 1908);
PAINT VIOLET (-2787 1908);
FORCEPROP 2 LAST CDS_LIB mstr_standard
J 0
(-2725 1900);
PAINT ORANGE (-2725 1900);
DISPLAY INVISIBLE (-2725 1900);
FORCEPROP 1 LAST PATH I87
J 0
(-2727 1900);
DISPLAY 0.872340 (-2727 1900);
PAINT GREEN (-2727 1900);
DISPLAY INVISIBLE (-2727 1900);
FORCEPROP 1 LAST BODY_TYPE PLUMBING
J 0
(-2725 1950);
DISPLAY 1.170213 (-2725 1950);
PAINT GREEN (-2725 1950);
DISPLAY INVISIBLE (-2725 1950);
FORCEPROP 1 LAST HDL_TAP TRUE
J 0
(-2400 1775);
DISPLAY 1.170213 (-2400 1775);
PAINT ORANGE (-2400 1775);
DISPLAY INVISIBLE (-2400 1775);
FORCEADD LBG_CORE_QAT_EXT_D..4
(-3925 2150);
FORCEPROP 1 LAST LOCATION U7C1
J 0
(-4675 3400);
DISPLAY 0.617021 (-4675 3400);
PAINT AQUA (-4675 3400);
FORCEPROP 1 LAST PART_NUMBER H91415-002
J 0
(-4675 950);
DISPLAY 0.617021 (-4675 950);
PAINT BLUE (-4675 950);
FORCEPROP 1 LAST MATERIAL IC
J 0
(-4675 3350);
DISPLAY 0.617021 (-4675 3350);
PAINT SKYBLUE (-4675 3350);
FORCEPROP 2 LASTPIN (-4725 3100) $PN C45
J 2
(-4735 3110);
DISPLAY 0.617021 (-4735 3110);
PAINT ORANGE (-4735 3110);
FORCEPROP 2 LASTPIN (-4725 3000) $PN D44
J 2
(-4735 3010);
DISPLAY 0.617021 (-4735 3010);
PAINT ORANGE (-4735 3010);
FORCEPROP 2 LASTPIN (-4725 2900) $PN C43
J 2
(-4735 2910);
DISPLAY 0.617021 (-4735 2910);
PAINT ORANGE (-4735 2910);
FORCEPROP 2 LASTPIN (-4725 2800) $PN D42
J 2
(-4735 2810);
DISPLAY 0.617021 (-4735 2810);
PAINT ORANGE (-4735 2810);
FORCEPROP 2 LASTPIN (-4725 3150) $PN A45
J 2
(-4735 3160);
DISPLAY 0.617021 (-4735 3160);
PAINT ORANGE (-4735 3160);
FORCEPROP 2 LASTPIN (-4725 3050) $PN B44
J 2
(-4735 3060);
DISPLAY 0.617021 (-4735 3060);
PAINT ORANGE (-4735 3060);
FORCEPROP 2 LASTPIN (-4725 2950) $PN A43
J 2
(-4735 2960);
DISPLAY 0.617021 (-4735 2960);
PAINT ORANGE (-4735 2960);
FORCEPROP 2 LASTPIN (-4725 2850) $PN B42
J 2
(-4735 2860);
DISPLAY 0.617021 (-4735 2860);
PAINT ORANGE (-4735 2860);
FORCEPROP 2 LASTPIN (-3125 3100) $PN P52
J 0
(-3115 3110);
DISPLAY 0.617021 (-3115 3110);
PAINT ORANGE (-3115 3110);
FORCEPROP 2 LASTPIN (-3125 3000) $PN K50
J 0
(-3115 3010);
DISPLAY 0.617021 (-3115 3010);
PAINT ORANGE (-3115 3010);
FORCEPROP 2 LASTPIN (-3125 2900) $PN J48
J 0
(-3115 2910);
DISPLAY 0.617021 (-3115 2910);
PAINT ORANGE (-3115 2910);
FORCEPROP 2 LASTPIN (-3125 2800) $PN H46
J 0
(-3115 2810);
DISPLAY 0.617021 (-3115 2810);
PAINT ORANGE (-3115 2810);
FORCEPROP 2 LASTPIN (-3125 3150) $PN N54
J 0
(-3115 3160);
DISPLAY 0.617021 (-3115 3160);
PAINT ORANGE (-3115 3160);
FORCEPROP 2 LASTPIN (-3125 3050) $PN M52
J 0
(-3115 3060);
DISPLAY 0.617021 (-3115 3060);
PAINT ORANGE (-3115 3060);
FORCEPROP 2 LASTPIN (-3125 2950) $PN H50
J 0
(-3115 2960);
DISPLAY 0.617021 (-3115 2960);
PAINT ORANGE (-3115 2960);
FORCEPROP 2 LASTPIN (-3125 2850) $PN K46
J 0
(-3115 2860);
DISPLAY 0.617021 (-3115 2860);
PAINT ORANGE (-3115 2860);
FORCEPROP 2 LASTPIN (-4725 1150) $PN C48
J 2
(-4735 1160);
DISPLAY 0.617021 (-4735 1160);
PAINT ORANGE (-4735 1160);
FORCEPROP 2 LASTPIN (-4725 1200) $PN A48
J 2
(-4735 1210);
DISPLAY 0.617021 (-4735 1210);
PAINT ORANGE (-4735 1210);
FORCEPROP 2 LASTPIN (-3125 1150) $PN J52
J 0
(-3115 1160);
DISPLAY 0.617021 (-3115 1160);
PAINT ORANGE (-3115 1160);
FORCEPROP 2 LASTPIN (-3125 1200) $PN G52
J 0
(-3115 1210);
DISPLAY 0.617021 (-3115 1210);
PAINT ORANGE (-3115 1210);
FORCEPROP 2 LASTPIN (-4725 2150) $PN C59
J 2
(-4735 2160);
DISPLAY 0.617021 (-4735 2160);
PAINT ORANGE (-4735 2160);
FORCEPROP 2 LASTPIN (-4725 2200) $PN A59
J 2
(-4735 2210);
DISPLAY 0.617021 (-4735 2210);
PAINT ORANGE (-4735 2210);
FORCEPROP 2 LASTPIN (-3125 2150) $PN N65
J 0
(-3115 2160);
DISPLAY 0.617021 (-3115 2160);
PAINT ORANGE (-3115 2160);
FORCEPROP 2 LASTPIN (-3125 2200) $PN P66
J 0
(-3115 2210);
DISPLAY 0.617021 (-3115 2210);
PAINT ORANGE (-3115 2210);
FORCEPROP 2 LASTPIN (-4725 2250) $PN D60
J 2
(-4735 2260);
DISPLAY 0.617021 (-4735 2260);
PAINT ORANGE (-4735 2260);
FORCEPROP 2 LASTPIN (-4725 2300) $PN B60
J 2
(-4735 2310);
DISPLAY 0.617021 (-4735 2310);
PAINT ORANGE (-4735 2310);
FORCEPROP 2 LASTPIN (-3125 2250) $PN T59
J 0
(-3115 2260);
DISPLAY 0.617021 (-3115 2260);
PAINT ORANGE (-3115 2260);
FORCEPROP 2 LASTPIN (-3125 2300) $PN V59
J 0
(-3115 2310);
DISPLAY 0.617021 (-3115 2310);
PAINT ORANGE (-3115 2310);
FORCEPROP 2 LASTPIN (-4725 2350) $PN C61
J 2
(-4735 2360);
DISPLAY 0.617021 (-4735 2360);
PAINT ORANGE (-4735 2360);
FORCEPROP 2 LASTPIN (-4725 2400) $PN A61
J 2
(-4735 2410);
DISPLAY 0.617021 (-4735 2410);
PAINT ORANGE (-4735 2410);
FORCEPROP 2 LASTPIN (-3125 2350) $PN R65
J 0
(-3115 2360);
DISPLAY 0.617021 (-3115 2360);
PAINT ORANGE (-3115 2360);
FORCEPROP 2 LASTPIN (-3125 2400) $PN U65
J 0
(-3115 2410);
DISPLAY 0.617021 (-3115 2410);
PAINT ORANGE (-3115 2410);
FORCEPROP 2 LASTPIN (-4725 2450) $PN D62
J 2
(-4735 2460);
DISPLAY 0.617021 (-4735 2460);
PAINT ORANGE (-4735 2460);
FORCEPROP 2 LASTPIN (-4725 2500) $PN B62
J 2
(-4735 2510);
DISPLAY 0.617021 (-4735 2510);
PAINT ORANGE (-4735 2510);
FORCEPROP 2 LASTPIN (-3125 2450) $PN T63
J 0
(-3115 2460);
DISPLAY 0.617021 (-3115 2460);
PAINT ORANGE (-3115 2460);
FORCEPROP 2 LASTPIN (-3125 2500) $PN U61
J 0
(-3115 2510);
DISPLAY 0.617021 (-3115 2510);
PAINT ORANGE (-3115 2510);
FORCEPROP 2 LASTPIN (-4725 2550) $PN C63
J 2
(-4735 2560);
DISPLAY 0.617021 (-4735 2560);
PAINT ORANGE (-4735 2560);
FORCEPROP 2 LASTPIN (-4725 2600) $PN A63
J 2
(-4735 2610);
DISPLAY 0.617021 (-4735 2610);
PAINT ORANGE (-4735 2610);
FORCEPROP 2 LASTPIN (-3125 2550) $PN W65
J 0
(-3115 2560);
DISPLAY 0.617021 (-3115 2560);
PAINT ORANGE (-3115 2560);
FORCEPROP 2 LASTPIN (-3125 2600) $PN V63
J 0
(-3115 2610);
DISPLAY 0.617021 (-3115 2610);
PAINT ORANGE (-3115 2610);
FORCEPROP 2 LASTPIN (-4725 2650) $PN D64
J 2
(-4735 2660);
DISPLAY 0.617021 (-4735 2660);
PAINT ORANGE (-4735 2660);
FORCEPROP 2 LASTPIN (-4725 2700) $PN B64
J 2
(-4735 2710);
DISPLAY 0.617021 (-4735 2710);
PAINT ORANGE (-4735 2710);
FORCEPROP 2 LASTPIN (-3125 2650) $PN Y66
J 0
(-3115 2660);
DISPLAY 0.617021 (-3115 2660);
PAINT ORANGE (-3115 2660);
FORCEPROP 2 LASTPIN (-3125 2700) $PN AA65
J 0
(-3115 2710);
DISPLAY 0.617021 (-3115 2710);
PAINT ORANGE (-3115 2710);
FORCEPROP 2 LASTPIN (-4725 1250) $PN D49
J 2
(-4735 1260);
DISPLAY 0.617021 (-4735 1260);
PAINT ORANGE (-4735 1260);
FORCEPROP 2 LASTPIN (-4725 1300) $PN B49
J 2
(-4735 1310);
DISPLAY 0.617021 (-4735 1310);
PAINT ORANGE (-4735 1310);
FORCEPROP 2 LASTPIN (-3125 1250) $PN P56
J 0
(-3115 1260);
DISPLAY 0.617021 (-3115 1260);
PAINT ORANGE (-3115 1260);
FORCEPROP 2 LASTPIN (-3125 1300) $PN M56
J 0
(-3115 1310);
DISPLAY 0.617021 (-3115 1310);
PAINT ORANGE (-3115 1310);
FORCEPROP 2 LASTPIN (-4725 1350) $PN C50
J 2
(-4735 1360);
DISPLAY 0.617021 (-4735 1360);
PAINT ORANGE (-4735 1360);
FORCEPROP 2 LASTPIN (-4725 1400) $PN A50
J 2
(-4735 1410);
DISPLAY 0.617021 (-4735 1410);
PAINT ORANGE (-4735 1410);
FORCEPROP 2 LASTPIN (-3125 1350) $PN H54
J 0
(-3115 1360);
DISPLAY 0.617021 (-3115 1360);
PAINT ORANGE (-3115 1360);
FORCEPROP 2 LASTPIN (-3125 1400) $PN G56
J 0
(-3115 1410);
DISPLAY 0.617021 (-3115 1410);
PAINT ORANGE (-3115 1410);
FORCEPROP 2 LASTPIN (-4725 1450) $PN D51
J 2
(-4735 1460);
DISPLAY 0.617021 (-4735 1460);
PAINT ORANGE (-4735 1460);
FORCEPROP 2 LASTPIN (-4725 1500) $PN B51
J 2
(-4735 1510);
DISPLAY 0.617021 (-4735 1510);
PAINT ORANGE (-4735 1510);
FORCEPROP 2 LASTPIN (-3125 1450) $PN J56
J 0
(-3115 1460);
DISPLAY 0.617021 (-3115 1460);
PAINT ORANGE (-3115 1460);
FORCEPROP 2 LASTPIN (-4725 1550) $PN C52
J 2
(-4735 1560);
DISPLAY 0.617021 (-4735 1560);
PAINT ORANGE (-4735 1560);
FORCEPROP 2 LASTPIN (-4725 1600) $PN A52
J 2
(-4735 1610);
DISPLAY 0.617021 (-4735 1610);
PAINT ORANGE (-4735 1610);
FORCEPROP 2 LASTPIN (-3125 1550) $PN N58
J 0
(-3115 1560);
DISPLAY 0.617021 (-3115 1560);
PAINT ORANGE (-3115 1560);
FORCEPROP 2 LASTPIN (-3125 1600) $PN M59
J 0
(-3115 1610);
DISPLAY 0.617021 (-3115 1610);
PAINT ORANGE (-3115 1610);
FORCEPROP 2 LASTPIN (-4725 1650) $PN D53
J 2
(-4735 1660);
DISPLAY 0.617021 (-4735 1660);
PAINT ORANGE (-4735 1660);
FORCEPROP 2 LASTPIN (-4725 1700) $PN B53
J 2
(-4735 1710);
DISPLAY 0.617021 (-4735 1710);
PAINT ORANGE (-4735 1710);
FORCEPROP 2 LASTPIN (-3125 1650) $PN N61
J 0
(-3115 1660);
DISPLAY 0.617021 (-3115 1660);
PAINT ORANGE (-3115 1660);
FORCEPROP 2 LASTPIN (-3125 1700) $PN K61
J 0
(-3115 1710);
DISPLAY 0.617021 (-3115 1710);
PAINT ORANGE (-3115 1710);
FORCEPROP 2 LASTPIN (-4725 1750) $PN C54
J 2
(-4735 1760);
DISPLAY 0.617021 (-4735 1760);
PAINT ORANGE (-4735 1760);
FORCEPROP 2 LASTPIN (-4725 1800) $PN A54
J 2
(-4735 1810);
DISPLAY 0.617021 (-4735 1810);
PAINT ORANGE (-4735 1810);
FORCEPROP 2 LASTPIN (-3125 1750) $PN H61
J 0
(-3115 1760);
DISPLAY 0.617021 (-3115 1760);
PAINT ORANGE (-3115 1760);
FORCEPROP 2 LASTPIN (-3125 1800) $PN J63
J 0
(-3115 1810);
DISPLAY 0.617021 (-3115 1810);
PAINT ORANGE (-3115 1810);
FORCEPROP 2 LASTPIN (-4725 1850) $PN D55
J 2
(-4735 1860);
DISPLAY 0.617021 (-4735 1860);
PAINT ORANGE (-4735 1860);
FORCEPROP 2 LASTPIN (-4725 1900) $PN B55
J 2
(-4735 1910);
DISPLAY 0.617021 (-4735 1910);
PAINT ORANGE (-4735 1910);
FORCEPROP 2 LASTPIN (-3125 1850) $PN P59
J 0
(-3115 1860);
DISPLAY 0.617021 (-3115 1860);
PAINT ORANGE (-3115 1860);
FORCEPROP 2 LASTPIN (-3125 1900) $PN R61
J 0
(-3115 1910);
DISPLAY 0.617021 (-3115 1910);
PAINT ORANGE (-3115 1910);
FORCEPROP 2 LASTPIN (-4725 1950) $PN C57
J 2
(-4735 1960);
DISPLAY 0.617021 (-4735 1960);
PAINT ORANGE (-4735 1960);
FORCEPROP 2 LASTPIN (-4725 2000) $PN A57
J 2
(-4735 2010);
DISPLAY 0.617021 (-4735 2010);
PAINT ORANGE (-4735 2010);
FORCEPROP 2 LASTPIN (-3125 1950) $PN K65
J 0
(-3115 1960);
DISPLAY 0.617021 (-3115 1960);
PAINT ORANGE (-3115 1960);
FORCEPROP 2 LASTPIN (-3125 2000) $PN M63
J 0
(-3115 2010);
DISPLAY 0.617021 (-3115 2010);
PAINT ORANGE (-3115 2010);
FORCEPROP 2 LASTPIN (-4725 2050) $PN D58
J 2
(-4735 2060);
DISPLAY 0.617021 (-4735 2060);
PAINT ORANGE (-4735 2060);
FORCEPROP 2 LASTPIN (-4725 2100) $PN B58
J 2
(-4735 2110);
DISPLAY 0.617021 (-4735 2110);
PAINT ORANGE (-4735 2110);
FORCEPROP 2 LASTPIN (-3125 2050) $PN J66
J 0
(-3115 2060);
DISPLAY 0.617021 (-3115 2060);
PAINT ORANGE (-3115 2060);
FORCEPROP 2 LASTPIN (-3125 2100) $PN M66
J 0
(-3115 2110);
DISPLAY 0.617021 (-3115 2110);
PAINT ORANGE (-3115 2110);
FORCEPROP 2 LASTPIN (-3125 1500) $PN K58
J 0
(-3115 1510);
DISPLAY 0.617021 (-3115 1510);
PAINT ORANGE (-3115 1510);
FORCEPROP 1 LAST PACK_TYPE BGA1
J 0
(-4675 3450);
PAINT SKYBLUE (-4675 3450);
DISPLAY INVISIBLE (-4675 3450);
FORCEPROP 2 LAST SEC_TYPE BGA1
J 0
(-4675 3450);
DISPLAY 1.021277 (-4675 3450);
PAINT ORANGE (-4675 3450);
DISPLAY INVISIBLE (-4675 3450);
FORCEPROP 2 LAST SEC 4
J 0
(-4675 3450);
DISPLAY 0.680851 (-4675 3450);
PAINT MONO (-4675 3450);
DISPLAY INVISIBLE (-4675 3450);
FORCEPROP 2 LAST CDS_LIB mstr_u_proc
J 0
(-3925 2150);
PAINT ORANGE (-3925 2150);
DISPLAY INVISIBLE (-3925 2150);
FORCEPROP 0 LAST BOM_COST SB
J 0
(-4675 3600);
DISPLAY 1.361702 (-4675 3600);
PAINT ORANGE (-4675 3600);
DISPLAY INVISIBLE (-4675 3600);
FORCEPROP 2 LAST CDS_LOCATION U7C1
J 0
(-4675 3400);
DISPLAY 0.617021 (-4675 3400);
PAINT AQUA (-4675 3400);
DISPLAY INVISIBLE (-4675 3400);
FORCEPROP 1 LAST PATH I9
J 0
(-3925 3350);
PAINT GREEN (-3925 3350);
DISPLAY INVISIBLE (-3925 3350);
FORCEPROP 0 LAST ROOM SB
J 0
(-4675 3500);
DISPLAY 1.361702 (-4675 3500);
PAINT ORANGE (-4675 3500);
DISPLAY INVISIBLE (-4675 3500);
FORCEADD TAP..1
(-2600 1750);
FORCEPROP 3 LASTPIN (-2650 1750) SIG_NAME P3E_CPU0_PE1_PCH_RXN<6>
J 0
(-2640 1760);
DISPLAY 0.659574 (-2640 1760);
PAINT MONO (-2640 1760);
DISPLAY INVISIBLE (-2640 1760);
FORCEPROP 1 LASTPIN (-2650 1750) BN 6
J 0
(-2662 1758);
DISPLAY 0.617021 (-2662 1758);
PAINT VIOLET (-2662 1758);
FORCEPROP 2 LAST CDS_LIB mstr_standard
J 0
(-2600 1750);
PAINT ORANGE (-2600 1750);
DISPLAY INVISIBLE (-2600 1750);
FORCEPROP 1 LAST PATH I90
J 0
(-2602 1750);
DISPLAY 0.872340 (-2602 1750);
PAINT GREEN (-2602 1750);
DISPLAY INVISIBLE (-2602 1750);
FORCEPROP 1 LAST BODY_TYPE PLUMBING
J 0
(-2600 1800);
DISPLAY 1.170213 (-2600 1800);
PAINT GREEN (-2600 1800);
DISPLAY INVISIBLE (-2600 1800);
FORCEPROP 1 LAST HDL_TAP TRUE
J 0
(-2275 1625);
DISPLAY 1.170213 (-2275 1625);
PAINT ORANGE (-2275 1625);
DISPLAY INVISIBLE (-2275 1625);
FORCEADD TAP..1
(-2600 1850);
FORCEPROP 3 LASTPIN (-2650 1850) SIG_NAME P3E_CPU0_PE1_PCH_RXN<7>
J 0
(-2640 1860);
DISPLAY 0.659574 (-2640 1860);
PAINT MONO (-2640 1860);
DISPLAY INVISIBLE (-2640 1860);
FORCEPROP 1 LASTPIN (-2650 1850) BN 7
J 0
(-2662 1858);
DISPLAY 0.617021 (-2662 1858);
PAINT VIOLET (-2662 1858);
FORCEPROP 2 LAST CDS_LIB mstr_standard
J 0
(-2600 1850);
PAINT ORANGE (-2600 1850);
DISPLAY INVISIBLE (-2600 1850);
FORCEPROP 1 LAST PATH I91
J 0
(-2602 1850);
DISPLAY 0.872340 (-2602 1850);
PAINT GREEN (-2602 1850);
DISPLAY INVISIBLE (-2602 1850);
FORCEPROP 1 LAST BODY_TYPE PLUMBING
J 0
(-2600 1900);
DISPLAY 1.170213 (-2600 1900);
PAINT GREEN (-2600 1900);
DISPLAY INVISIBLE (-2600 1900);
FORCEPROP 1 LAST HDL_TAP TRUE
J 0
(-2275 1725);
DISPLAY 1.170213 (-2275 1725);
PAINT ORANGE (-2275 1725);
DISPLAY INVISIBLE (-2275 1725);
FORCEADD OFFPAGE..2
(-1325 1025);
FORCEPROP 2 LAST $XR0 107 
J 0
(-1136 1025);
DISPLAY 0.638298 (-1136 1025);
PAINT MONO (-1136 1025);
FORCEPROP 2 LAST CDS_LIB mstr_standard
J 0
(-1325 1025);
PAINT ORANGE (-1325 1025);
DISPLAY INVISIBLE (-1325 1025);
FORCEPROP 2 LAST PATH I95
J 0
(-1125 1075);
DISPLAY 1.021277 (-1125 1075);
PAINT ORANGE (-1125 1075);
DISPLAY INVISIBLE (-1125 1075);
FORCEPROP 1 LAST OFFPAGE TRUE
J 0
(-1000 900);
DISPLAY 1.170213 (-1000 900);
PAINT GREEN (-1000 900);
DISPLAY INVISIBLE (-1000 900);
FORCEPROP 1 LAST COMMENT_BODY TRUE
J 0
(-1370 930);
DISPLAY 1.170213 (-1370 930);
PAINT PEACH (-1370 930);
DISPLAY INVISIBLE (-1370 930);
FORCEADD OFFPAGE..2
(-1325 1100);
FORCEPROP 2 LAST $XR0 107 
J 0
(-1136 1100);
DISPLAY 0.638298 (-1136 1100);
PAINT MONO (-1136 1100);
FORCEPROP 2 LAST CDS_LIB mstr_standard
J 0
(-1325 1100);
PAINT ORANGE (-1325 1100);
DISPLAY INVISIBLE (-1325 1100);
FORCEPROP 2 LAST PATH I96
J 0
(-1125 1150);
DISPLAY 1.021277 (-1125 1150);
PAINT ORANGE (-1125 1150);
DISPLAY INVISIBLE (-1125 1150);
FORCEPROP 1 LAST OFFPAGE TRUE
J 0
(-1000 975);
DISPLAY 1.170213 (-1000 975);
PAINT GREEN (-1000 975);
DISPLAY INVISIBLE (-1000 975);
FORCEPROP 1 LAST COMMENT_BODY TRUE
J 0
(-1370 1005);
DISPLAY 1.170213 (-1370 1005);
PAINT PEACH (-1370 1005);
DISPLAY INVISIBLE (-1370 1005);
FORCEADD TAP..6
(-5500 2000);
FORCEPROP 3 LASTPIN (-5450 2000) SIG_NAME P3E_CPU0_PE1_PCH_C_TXN<8>
J 0
(-5440 2010);
DISPLAY 0.659574 (-5440 2010);
PAINT MONO (-5440 2010);
DISPLAY INVISIBLE (-5440 2010);
FORCEPROP 1 LASTPIN (-5450 2000) BN 8
J 0
(-5502 2008);
DISPLAY 0.617021 (-5502 2008);
PAINT GREEN (-5502 2008);
FORCEPROP 2 LAST CDS_LIB mstr_standard
J 0
(-5500 2000);
PAINT ORANGE (-5500 2000);
DISPLAY INVISIBLE (-5500 2000);
FORCEPROP 1 LAST PATH I97
J 0
(-5502 2000);
DISPLAY 0.872340 (-5502 2000);
PAINT GREEN (-5502 2000);
DISPLAY INVISIBLE (-5502 2000);
FORCEPROP 1 LAST BODY_TYPE PLUMBING
J 0
(-5500 1950);
DISPLAY 1.170213 (-5500 1950);
PAINT GREEN (-5500 1950);
DISPLAY INVISIBLE (-5500 1950);
FORCEPROP 1 LAST HDL_TAP TRUE
J 0
(-5175 1875);
DISPLAY 1.170213 (-5175 1875);
PAINT ORANGE (-5175 1875);
DISPLAY INVISIBLE (-5175 1875);
FORCEADD TAP..6
(-5500 2100);
FORCEPROP 3 LASTPIN (-5450 2100) SIG_NAME P3E_CPU0_PE1_PCH_C_TXN<9>
J 0
(-5440 2110);
DISPLAY 0.659574 (-5440 2110);
PAINT MONO (-5440 2110);
DISPLAY INVISIBLE (-5440 2110);
FORCEPROP 1 LASTPIN (-5450 2100) BN 9
J 0
(-5502 2108);
DISPLAY 0.617021 (-5502 2108);
PAINT GREEN (-5502 2108);
FORCEPROP 2 LAST CDS_LIB mstr_standard
J 0
(-5500 2100);
PAINT ORANGE (-5500 2100);
DISPLAY INVISIBLE (-5500 2100);
FORCEPROP 1 LAST PATH I98
J 0
(-5502 2100);
DISPLAY 0.872340 (-5502 2100);
PAINT GREEN (-5502 2100);
DISPLAY INVISIBLE (-5502 2100);
FORCEPROP 1 LAST BODY_TYPE PLUMBING
J 0
(-5500 2050);
DISPLAY 1.170213 (-5500 2050);
PAINT GREEN (-5500 2050);
DISPLAY INVISIBLE (-5500 2050);
FORCEPROP 1 LAST HDL_TAP TRUE
J 0
(-5175 1975);
DISPLAY 1.170213 (-5175 1975);
PAINT ORANGE (-5175 1975);
DISPLAY INVISIBLE (-5175 1975);
FORCEADD TAP..6
(-5500 2200);
FORCEPROP 3 LASTPIN (-5450 2200) SIG_NAME P3E_CPU0_PE1_PCH_C_TXN<10>
J 0
(-5440 2210);
DISPLAY 0.659574 (-5440 2210);
PAINT MONO (-5440 2210);
DISPLAY INVISIBLE (-5440 2210);
FORCEPROP 1 LASTPIN (-5450 2200) BN 10
J 0
(-5502 2208);
DISPLAY 0.617021 (-5502 2208);
PAINT GREEN (-5502 2208);
FORCEPROP 2 LAST CDS_LIB mstr_standard
J 0
(-5500 2200);
PAINT ORANGE (-5500 2200);
DISPLAY INVISIBLE (-5500 2200);
FORCEPROP 1 LAST PATH I99
J 0
(-5502 2200);
DISPLAY 0.872340 (-5502 2200);
PAINT GREEN (-5502 2200);
DISPLAY INVISIBLE (-5502 2200);
FORCEPROP 1 LAST BODY_TYPE PLUMBING
J 0
(-5500 2150);
DISPLAY 1.170213 (-5500 2150);
PAINT GREEN (-5500 2150);
DISPLAY INVISIBLE (-5500 2150);
FORCEPROP 1 LAST HDL_TAP TRUE
J 0
(-5175 2075);
DISPLAY 1.170213 (-5175 2075);
PAINT ORANGE (-5175 2075);
DISPLAY INVISIBLE (-5175 2075);
FORCEADD DESIGN_NOTE..1
(-1875 825);
FORCEPROP 0 LAST L2 TO PCH PCIEUP OR X24 SUPSERSLOT
J 0
(-2075 625);
DISPLAY 1.021277 (-2075 625);
PAINT ORANGE (-2075 625);
FORCEPROP 0 LAST L1 CPU0 HAS THE STEERING OPTION TO GO
J 0
(-2075 700);
DISPLAY 1.021277 (-2075 700);
PAINT ORANGE (-2075 700);
FORCEPROP 2 LAST CDS_LIB mstr_symbols
J 0
(-1875 825);
PAINT ORANGE (-1875 825);
DISPLAY INVISIBLE (-1875 825);
FORCEPROP 1 LAST COMMENT_BODY TRUE
J 0
(-1850 925);
DISPLAY 0.978723 (-1850 925);
PAINT ORANGE (-1850 925);
DISPLAY INVISIBLE (-1850 925);
FORCEADD DESIGN_NOTE..1
(-7375 2425);
FORCEPROP 0 LAST L2 INVERTED FOR EASE OF ROUTING
J 0
(-7575 2225);
DISPLAY 1.021277 (-7575 2225);
PAINT ORANGE (-7575 2225);
FORCEPROP 0 LAST L1 LANES 15:12, 10:8 ARE POLARITY
J 0
(-7575 2300);
DISPLAY 1.021277 (-7575 2300);
PAINT ORANGE (-7575 2300);
FORCEPROP 2 LAST CDS_LIB mstr_symbols
J 0
(-7375 2425);
PAINT ORANGE (-7375 2425);
DISPLAY INVISIBLE (-7375 2425);
FORCEPROP 1 LAST COMMENT_BODY TRUE
J 0
(-7350 2525);
DISPLAY 0.978723 (-7350 2525);
PAINT ORANGE (-7350 2525);
DISPLAY INVISIBLE (-7350 2525);
FORCEADD INTEL_CORP_BPAGE..1
(0 0);
FORCEPROP 1 LAST CDS_CON_LAST_MODIFIED Fri Jun 16 17:48:46 2017
J 0
(-1425 325);
DISPLAY 1.340426 (-1425 325);
PAINT ORANGE (-1425 325);
DISPLAY INVISIBLE (-1425 325);
FORCEPROP 1 LAST CUSTOM_TXT_CDS <CURRENT_DESIGN_SHEET> OF <TOTAL_DESIGN_SHEETS>
J 0
(-500 25);
PAINT ORANGE (-500 25);
FORCEPROP 1 LAST CUSTOM_TXT_CDS <CON_LAST_MODIFIED>
J 0
(-4000 100);
PAINT ORANGE (-4000 100);
FORCEPROP 2 LAST CUSTOM_TXT_CDS <XR_PAGE_TITLE>
J 0
(-7890 5250);
DISPLAY 0.638298 (-7890 5250);
PAINT PINK (-7890 5250);
DISPLAY INVISIBLE (-7890 5250);
FORCEPROP 1 LAST SCH_TITLE LEWISBURG 4/11 DMI, PCIE
J 0
(-7950 50);
DISPLAY 1.212766 (-7950 50);
PAINT YELLOW (-7950 50);
FORCEPROP 2 LAST PAGE_BORDER TRUE
J 0
(-7890 5250);
DISPLAY 0.851064 (-7890 5250);
PAINT PINK (-7890 5250);
DISPLAY INVISIBLE (-7890 5250);
FORCEPROP 2 LAST CDS_LIB mstr_symbols
J 0
(0 0);
PAINT ORANGE (0 0);
DISPLAY INVISIBLE (0 0);
FORCEPROP 1 LAST COMMENT_BODY TRUE
J 0
(12 12);
DISPLAY 0.638298 (12 12);
PAINT PEACH (12 12);
DISPLAY INVISIBLE (12 12);
FORCEPROP 2 LAST CDS_XR_PAGE_TITLE CR-117 : @BASEBOARD_FAB2_LIB.BASEBOARD_FAB2(SCH_1):PAGE117
J 0
(-7890 5250);
DISPLAY 0.638298 (-7890 5250);
PAINT PINK (-7890 5250);
DISPLAY INVISIBLE (-7890 5250);
FORCEADD DESIGN_NOTE..1
(-6250 825);
FORCEPROP 0 LAST L1 CPU0 HAS THE STEERING OPTION TO GO
J 0
(-6450 700);
DISPLAY 1.021277 (-6450 700);
PAINT ORANGE (-6450 700);
FORCEPROP 0 LAST L2 TO PCH PCIEUP OR X24 SUPSERSLOT
J 0
(-6450 625);
DISPLAY 1.021277 (-6450 625);
PAINT ORANGE (-6450 625);
FORCEPROP 2 LAST CDS_LIB mstr_symbols
J 0
(-6250 825);
PAINT ORANGE (-6250 825);
DISPLAY INVISIBLE (-6250 825);
FORCEPROP 1 LAST COMMENT_BODY TRUE
J 0
(-6225 925);
DISPLAY 0.978723 (-6225 925);
PAINT ORANGE (-6225 925);
DISPLAY INVISIBLE (-6225 925);
WIRE 17 -1 (-6450 3350)(-5475 3350);
FORCEPROP 2 LAST SIG_NAME DMI_CPU0_PCH_TX_C_DP<3:0>
J 0
(-6435 3360);
DISPLAY 0.617021 (-6435 3360);
PAINT ORANGE (-6435 3360);
WIRE 17 -1 (-5475 3350)(-5475 3175);
WIRE 17 -1 (-5475 2975)(-5475 2875);
WIRE 17 -1 (-5475 3175)(-5475 3075);
WIRE 17 -1 (-5475 3075)(-5475 2975);
WIRE 17 -1 (-2550 2925)(-2550 2825);
WIRE 17 -1 (-2550 3025)(-2550 2925);
WIRE 17 -1 (-2550 3125)(-2550 3025);
WIRE 17 -1 (-1750 3250)(-2550 3250);
FORCEPROP 2 LAST SIG_NAME DMI_CPU0_PCH_RX_DN<3:0>
J 0
(-2535 3260);
DISPLAY 0.617021 (-2535 3260);
PAINT ORANGE (-2535 3260);
WIRE 17 -1 (-2550 3250)(-2550 3125);
WIRE 17 -1 (-2675 3350)(-1750 3350);
FORCEPROP 2 LAST SIG_NAME DMI_CPU0_PCH_RX_DP<3:0>
J 0
(-2535 3360);
DISPLAY 0.617021 (-2535 3360);
PAINT ORANGE (-2535 3360);
WIRE 17 -1 (-2675 3350)(-2675 3175);
WIRE 17 -1 (-2675 3175)(-2675 3075);
WIRE 17 -1 (-2675 3075)(-2675 2975);
WIRE 17 -1 (-2675 2975)(-2675 2875);
WIRE 17 -1 (-5675 1775)(-5675 1875);
WIRE 17 -1 (-5675 1775)(-5675 1675);
WIRE 17 -1 (-5675 1675)(-5675 1575);
WIRE 17 -1 (-5675 1575)(-5675 1475);
WIRE 17 -1 (-5675 1475)(-5675 1375);
WIRE 17 -1 (-5675 1100)(-6925 1100);
FORCEPROP 0 LAST SIG_NAME P3E_CPU0_PE1_PCH_TXN<7:0>
J 0
(-6910 1110);
DISPLAY 0.617021 (-6910 1110);
PAINT ORANGE (-6910 1110);
WIRE 17 -1 (-5675 1175)(-5675 1100);
WIRE 17 -1 (-5675 1375)(-5675 1275);
WIRE 17 -1 (-5675 1275)(-5675 1175);
WIRE 17 -1 (-5550 1825)(-5550 1925);
WIRE 17 -1 (-5550 1725)(-5550 1825);
WIRE 17 -1 (-5550 1625)(-5550 1725);
WIRE 17 -1 (-5550 1525)(-5550 1625);
WIRE 17 -1 (-5550 1025)(-6925 1025);
FORCEPROP 0 LAST SIG_NAME P3E_CPU0_PE1_PCH_TXP<7:0>
J 0
(-6910 1035);
DISPLAY 0.617021 (-6910 1035);
PAINT ORANGE (-6910 1035);
WIRE 17 -1 (-5550 1425)(-5550 1525);
WIRE 17 -1 (-5550 1325)(-5550 1425);
WIRE 17 -1 (-5550 1025)(-5550 1225);
WIRE 17 -1 (-5550 1225)(-5550 1325);
WIRE 17 -1 (-5675 2575)(-5675 2675);
WIRE 17 -1 (-5675 2475)(-5675 2575);
WIRE 17 -1 (-5675 2375)(-5675 2475);
WIRE 17 -1 (-5675 2325)(-5675 2375);
WIRE 17 -1 (-5675 1925)(-6650 1925);
FORCEPROP 2 LAST SIG_NAME P3E_CPU0_PE1_PCH_C_TXP<15:8>
J 0
(-6635 1935);
DISPLAY 0.617021 (-6635 1935);
PAINT ORANGE (-6635 1935);
WIRE 17 -1 (-5675 2175)(-5675 2325);
WIRE 17 -1 (-5675 2075)(-5675 2175);
WIRE 17 -1 (-5675 1975)(-5675 1925);
WIRE 17 -1 (-5675 1975)(-5675 2075);
WIRE 17 -1 (-5550 2725)(-5550 2625);
WIRE 17 -1 (-5550 2625)(-5550 2525);
WIRE 17 -1 (-5550 2525)(-5550 2425);
WIRE 17 -1 (-5550 2275)(-5550 2425);
WIRE 17 -1 (-5550 2225)(-5550 2275);
WIRE 17 -1 (-5550 2125)(-5550 2225);
WIRE 17 -1 (-5550 2025)(-6650 2025);
FORCEPROP 2 LAST SIG_NAME P3E_CPU0_PE1_PCH_C_TXN<15:8>
J 0
(-6635 2035);
DISPLAY 0.617021 (-6635 2035);
PAINT ORANGE (-6635 2035);
WIRE 17 -1 (-5550 2025)(-5550 2125);
WIRE 17 -1 (-5625 2925)(-5625 2825);
WIRE 17 -1 (-5625 3025)(-5625 2925);
WIRE 17 -1 (-5625 3125)(-5625 3025);
WIRE 17 -1 (-6450 3250)(-5625 3250);
FORCEPROP 2 LAST SIG_NAME DMI_CPU0_PCH_TX_C_DN<3:0>
J 0
(-6435 3260);
DISPLAY 0.617021 (-6435 3260);
PAINT ORANGE (-6435 3260);
WIRE 17 -1 (-5625 3250)(-5625 3125);
WIRE 17 -1 (-2550 1775)(-2550 1875);
WIRE 17 -1 (-2550 1775)(-2550 1675);
WIRE 17 -1 (-2550 1675)(-2550 1575);
WIRE 17 -1 (-2550 1575)(-2550 1475);
WIRE 17 -1 (-2550 1475)(-2550 1375);
WIRE 17 -1 (-2550 1100)(-1375 1100);
FORCEPROP 0 LAST SIG_NAME P3E_CPU0_PE1_PCH_RXN<7:0>
J 2
(-1360 1110);
DISPLAY 0.617021 (-1360 1110);
PAINT ORANGE (-1360 1110);
WIRE 17 -1 (-2550 1175)(-2550 1100);
WIRE 17 -1 (-2550 1375)(-2550 1275);
WIRE 17 -1 (-2550 1275)(-2550 1175);
WIRE 17 -1 (-2675 1825)(-2675 1925);
WIRE 17 -1 (-2675 1825)(-2675 1725);
WIRE 17 -1 (-2675 1725)(-2675 1625);
WIRE 17 -1 (-2675 1625)(-2675 1525);
WIRE 17 -1 (-2675 1525)(-2675 1425);
WIRE 17 -1 (-2675 1025)(-1375 1025);
FORCEPROP 0 LAST SIG_NAME P3E_CPU0_PE1_PCH_RXP<7:0>
J 2
(-1360 1035);
DISPLAY 0.617021 (-1360 1035);
PAINT ORANGE (-1360 1035);
WIRE 17 -1 (-2675 1225)(-2675 1025);
WIRE 17 -1 (-2675 1425)(-2675 1325);
WIRE 17 -1 (-2675 1325)(-2675 1225);
WIRE 17 -1 (-2550 2575)(-2550 2675);
WIRE 17 -1 (-2550 2475)(-2550 2575);
WIRE 17 -1 (-2550 2375)(-2550 2475);
WIRE 17 -1 (-2550 2275)(-2550 2375);
WIRE 17 -1 (-2550 1950)(-1400 1950);
FORCEPROP 2 LAST SIG_NAME P3E_CPU0_PE1_PCH_R_RXN<15:8>
J 0
(-2310 1960);
DISPLAY 0.617021 (-2310 1960);
PAINT ORANGE (-2310 1960);
WIRE 17 -1 (-2550 2175)(-2550 2275);
WIRE 17 -1 (-2550 2075)(-2550 2175);
WIRE 17 -1 (-2550 1975)(-2550 1950);
WIRE 17 -1 (-2550 1975)(-2550 2075);
WIRE 17 -1 (-2675 2625)(-2675 2725);
WIRE 17 -1 (-2675 2525)(-2675 2625);
WIRE 17 -1 (-2675 2425)(-2675 2525);
WIRE 17 -1 (-2675 2325)(-2675 2425);
WIRE 17 -1 (-2675 2225)(-2675 2325);
WIRE 17 -1 (-2675 2125)(-2675 2225);
WIRE 17 -1 (-2675 2025)(-2675 2125);
WIRE 17 -1 (-2675 2025)(-1425 2025);
FORCEPROP 2 LAST SIG_NAME P3E_CPU0_PE1_PCH_R_RXP<15:8>
J 0
(-2310 2035);
DISPLAY 0.617021 (-2310 2035);
PAINT ORANGE (-2310 2035);
WIRE 16 -1 (-5525 2900)(-4725 2900);
WIRE 16 -1 (-5525 3000)(-4725 3000);
WIRE 16 -1 (-3125 2100)(-2775 2100);
WIRE 16 -1 (-2650 2050)(-3125 2050);
WIRE 16 -1 (-3125 2700)(-2775 2700);
WIRE 16 -1 (-2650 2650)(-3125 2650);
WIRE 16 -1 (-3125 2600)(-2775 2600);
WIRE 16 -1 (-2650 2550)(-3125 2550);
WIRE 16 -1 (-3125 2500)(-2775 2500);
WIRE 16 -1 (-2650 2450)(-3125 2450);
WIRE 16 -1 (-3125 2400)(-2775 2400);
WIRE 16 -1 (-2650 2350)(-3125 2350);
WIRE 16 -1 (-3125 2300)(-2775 2300);
WIRE 16 -1 (-2650 2250)(-3125 2250);
WIRE 16 -1 (-3125 2200)(-2775 2200);
WIRE 16 -1 (-2650 2150)(-3125 2150);
WIRE 16 -1 (-2775 2950)(-3125 2950);
WIRE 16 -1 (-2775 3050)(-3125 3050);
WIRE 16 -1 (-3125 3150)(-2775 3150);
WIRE 16 -1 (-2650 2800)(-3125 2800);
WIRE 16 -1 (-2650 2900)(-3125 2900);
WIRE 16 -1 (-2650 3000)(-3125 3000);
WIRE 16 -1 (-3125 2000)(-2775 2000);
WIRE 16 -1 (-2650 1950)(-3125 1950);
WIRE 16 -1 (-3125 1900)(-2775 1900);
WIRE 16 -1 (-2650 1850)(-3125 1850);
WIRE 16 -1 (-3125 1800)(-2775 1800);
WIRE 16 -1 (-2650 1750)(-3125 1750);
WIRE 16 -1 (-3125 1700)(-2775 1700);
WIRE 16 -1 (-2650 1650)(-3125 1650);
WIRE 16 -1 (-3125 1600)(-2775 1600);
WIRE 16 -1 (-2650 1550)(-3125 1550);
WIRE 16 -1 (-3125 1500)(-2775 1500);
WIRE 16 -1 (-2650 1450)(-3125 1450);
WIRE 16 -1 (-3125 1400)(-2775 1400);
WIRE 16 -1 (-2650 1350)(-3125 1350);
WIRE 16 -1 (-3125 1300)(-2775 1300);
WIRE 16 -1 (-2650 1250)(-3125 1250);
WIRE 16 -1 (-3125 1200)(-2775 1200);
WIRE 16 -1 (-3125 1150)(-2650 1150);
WIRE 16 -1 (-5450 2100)(-4725 2100);
WIRE 16 -1 (-4725 2050)(-5575 2050);
WIRE 16 -1 (-5450 2700)(-4725 2700);
WIRE 16 -1 (-4725 2650)(-5575 2650);
WIRE 16 -1 (-5450 2600)(-4725 2600);
WIRE 16 -1 (-4725 2550)(-5575 2550);
WIRE 16 -1 (-5450 2500)(-4725 2500);
WIRE 16 -1 (-4725 2450)(-5575 2450);
WIRE 16 -1 (-5450 2400)(-4725 2400);
WIRE 16 -1 (-4725 2350)(-5575 2350);
WIRE 16 -1 (-5575 2300)(-4725 2300);
WIRE 16 -1 (-4725 2250)(-5450 2250);
WIRE 16 -1 (-4725 2200)(-5450 2200);
WIRE 16 -1 (-4725 2150)(-5575 2150);
WIRE 16 -1 (-5375 2850)(-4725 2850);
WIRE 16 -1 (-5375 3050)(-4725 3050);
WIRE 16 -1 (-5375 3150)(-4725 3150);
WIRE 16 -1 (-5525 2800)(-4725 2800);
WIRE 16 -1 (-5525 3100)(-4725 3100);
WIRE 16 -1 (-5450 2000)(-4725 2000);
WIRE 16 -1 (-4725 1950)(-5575 1950);
WIRE 16 -1 (-5450 1900)(-4725 1900);
WIRE 16 -1 (-5575 1850)(-4725 1850);
WIRE 16 -1 (-4725 1800)(-5450 1800);
WIRE 16 -1 (-4725 1750)(-5575 1750);
WIRE 16 -1 (-5450 1700)(-4725 1700);
WIRE 16 -1 (-5575 1650)(-4725 1650);
WIRE 16 -1 (-4725 1600)(-5450 1600);
WIRE 16 -1 (-4725 1550)(-5575 1550);
WIRE 16 -1 (-5450 1500)(-4725 1500);
WIRE 16 -1 (-5575 1450)(-4725 1450);
WIRE 16 -1 (-4725 1400)(-5450 1400);
WIRE 16 -1 (-5575 1350)(-4725 1350);
WIRE 16 -1 (-5450 1300)(-4725 1300);
WIRE 16 -1 (-5575 1250)(-4725 1250);
WIRE 16 -1 (-4725 1200)(-5450 1200);
WIRE 16 -1 (-4725 1150)(-5575 1150);
WIRE 16 -1 (-2775 2850)(-3125 2850);
WIRE 16 -1 (-3125 3100)(-2650 3100);
WIRE 16 -1 (-5375 2950)(-4725 2950);
FORCENOTE
ROOM=SB
(-7725 250) 0;
DISPLAY LEFT (-7725 250);
DISPLAY 1.021277 (-7725 250);
PAINT PURPLE (-7725 250);
FORCENOTE
CPU0
(-6925 900) 0;
DISPLAY LEFT (-6925 900);
DISPLAY 1.021277 (-6925 900);
PAINT PURPLE (-6925 900);
FORCENOTE
CPU0
(-6750 1775) 0;
DISPLAY LEFT (-6750 1775);
DISPLAY 1.021277 (-6750 1775);
PAINT PURPLE (-6750 1775);
FORCENOTE
CPU0 DMI
(-6375 3150) 0;
DISPLAY LEFT (-6375 3150);
DISPLAY 1.021277 (-6375 3150);
PAINT PURPLE (-6375 3150);
FORCENOTE
CPU0
(-1325 875) 0;
DISPLAY LEFT (-1325 875);
DISPLAY 1.021277 (-1325 875);
PAINT PURPLE (-1325 875);
FORCENOTE
CPU0
(-1425 1800) 0;
DISPLAY LEFT (-1425 1800);
DISPLAY 1.021277 (-1425 1800);
PAINT PURPLE (-1425 1800);
FORCENOTE
CPU0 DMI
(-1775 3075) 0;
DISPLAY LEFT (-1775 3075);
DISPLAY 1.021277 (-1775 3075);
PAINT PURPLE (-1775 3075);
QUIT
